(kicad_sch
	(version 20250114)
	(generator "eeschema")
	(generator_version "9.0")
	(paper "A3")
	(title_block
		(title "SO-DIMM DDR5 Tester")
		(date "2025-11-26")
		(rev "1.3.0")
		(company "Antmicro Ltd.")
		(comment 1 "www.antmicro.com")
		(comment 2 "Antmicro Ltd")
	)
	(text "L"
		(exclude_from_sim no)
		(at 164.465 240.03 0)
		(effects
			(font
				(size 1.27 1.27)
			)
			(justify left bottom)
		)
	)
	(text "ICT Testpoints"
		(exclude_from_sim no)
		(at 254.254 250.952 0)
		(effects
			(font
				(size 1.27 1.27)
				(thickness 0.254)
				(bold yes)
			)
			(justify left bottom)
		)
	)
	(text "PWR I2C MUX"
		(exclude_from_sim no)
		(at 15.24 142.24 0)
		(effects
			(font
				(size 2.54 2.54)
				(thickness 0.4978)
				(bold yes)
			)
			(justify left bottom)
		)
	)
	(text "L"
		(exclude_from_sim no)
		(at 160.02 243.205 0)
		(effects
			(font
				(size 1.27 1.27)
			)
			(justify left bottom)
		)
	)
	(text "FTDI"
		(exclude_from_sim no)
		(at 153.035 246.38 0)
		(effects
			(font
				(size 1.27 1.27)
			)
			(justify left bottom)
		)
	)
	(text "H"
		(exclude_from_sim no)
		(at 164.465 243.205 0)
		(effects
			(font
				(size 1.27 1.27)
			)
			(justify left bottom)
		)
	)
	(text "H"
		(exclude_from_sim no)
		(at 160.02 246.38 0)
		(effects
			(font
				(size 1.27 1.27)
			)
			(justify left bottom)
		)
	)
	(text "OFF"
		(exclude_from_sim no)
		(at 153.67 236.855 0)
		(effects
			(font
				(size 1.27 1.27)
			)
			(justify left bottom)
		)
	)
	(text "PWR I^{2}C"
		(exclude_from_sim no)
		(at 149.225 233.68 0)
		(effects
			(font
				(size 1.27 1.27)
				(thickness 0.254)
				(bold yes)
			)
			(justify left bottom)
		)
	)
	(text "I2C logic translator"
		(exclude_from_sim no)
		(at 15.875 19.685 0)
		(effects
			(font
				(size 2.54 2.54)
				(thickness 0.4978)
				(bold yes)
			)
			(justify left bottom)
		)
	)
	(text "H"
		(exclude_from_sim no)
		(at 164.465 246.38 0)
		(effects
			(font
				(size 1.27 1.27)
			)
			(justify left bottom)
		)
	)
	(text "Note:\nPlace on the bottom side "
		(exclude_from_sim no)
		(at 272.288 251.206 0)
		(effects
			(font
				(size 1.27 1.27)
			)
			(justify left)
		)
	)
	(text "0R Mux bypass"
		(exclude_from_sim no)
		(at 283.845 187.325 0)
		(effects
			(font
				(size 1.27 1.27)
			)
			(justify left bottom)
		)
	)
	(text "H"
		(exclude_from_sim no)
		(at 160.02 240.03 0)
		(effects
			(font
				(size 1.27 1.27)
			)
			(justify left bottom)
		)
	)
	(text "IN2"
		(exclude_from_sim no)
		(at 163.195 233.68 0)
		(effects
			(font
				(size 1.27 1.27)
				(thickness 0.254)
				(bold yes)
			)
			(justify left bottom)
		)
	)
	(text "L"
		(exclude_from_sim no)
		(at 160.02 236.855 0)
		(effects
			(font
				(size 1.27 1.27)
			)
			(justify left bottom)
		)
	)
	(text "I2C EEPROM with unique ID"
		(exclude_from_sim no)
		(at 218.186 21.082 0)
		(effects
			(font
				(size 2.54 2.54)
				(thickness 0.4978)
				(bold yes)
			)
			(justify left bottom)
		)
	)
	(text "IN1"
		(exclude_from_sim no)
		(at 158.75 233.68 0)
		(effects
			(font
				(size 1.27 1.27)
				(thickness 0.254)
				(bold yes)
			)
			(justify left bottom)
		)
	)
	(text "L"
		(exclude_from_sim no)
		(at 164.465 236.855 0)
		(effects
			(font
				(size 1.27 1.27)
			)
			(justify left bottom)
		)
	)
	(text "FPGA PWR I^{2}C"
		(exclude_from_sim no)
		(at 144.145 243.205 0)
		(effects
			(font
				(size 1.27 1.27)
			)
			(justify left bottom)
		)
	)
	(text "FPGA DDR I^{2}C"
		(exclude_from_sim no)
		(at 144.145 240.03 0)
		(effects
			(font
				(size 1.27 1.27)
			)
			(justify left bottom)
		)
	)
	(junction
		(at 86.36 76.2)
		(diameter 0)
		(color 0 0 0 0)
	)
	(junction
		(at 141.605 223.52)
		(diameter 0)
		(color 0 0 0 0)
	)
	(junction
		(at 120.015 177.165)
		(diameter 0)
		(color 0 0 0 0)
	)
	(junction
		(at 120.015 189.23)
		(diameter 0)
		(color 0 0 0 0)
	)
	(junction
		(at 127.635 82.55)
		(diameter 0)
		(color 0 0 0 0)
	)
	(junction
		(at 334.01 80.01)
		(diameter 0)
		(color 0 0 0 0)
	)
	(junction
		(at 123.19 213.36)
		(diameter 0)
		(color 0 0 0 0)
	)
	(junction
		(at 139.7 196.85)
		(diameter 0)
		(color 0 0 0 0)
	)
	(junction
		(at 300.99 198.755)
		(diameter 0)
		(color 0 0 0 0)
	)
	(junction
		(at 185.42 186.69)
		(diameter 0)
		(color 0 0 0 0)
	)
	(junction
		(at 83.185 82.55)
		(diameter 0)
		(color 0 0 0 0)
	)
	(junction
		(at 185.42 210.82)
		(diameter 0)
		(color 0 0 0 0)
	)
	(junction
		(at 124.46 76.2)
		(diameter 0)
		(color 0 0 0 0)
	)
	(junction
		(at 133.35 76.2)
		(diameter 0)
		(color 0 0 0 0)
	)
	(junction
		(at 300.99 207.645)
		(diameter 0)
		(color 0 0 0 0)
	)
	(junction
		(at 83.185 76.2)
		(diameter 0)
		(color 0 0 0 0)
	)
	(junction
		(at 86.36 85.09)
		(diameter 0)
		(color 0 0 0 0)
	)
	(junction
		(at 124.46 85.09)
		(diameter 0)
		(color 0 0 0 0)
	)
	(junction
		(at 299.72 77.47)
		(diameter 0)
		(color 0 0 0 0)
	)
	(junction
		(at 290.83 77.47)
		(diameter 0)
		(color 0 0 0 0)
	)
	(junction
		(at 139.065 65.405)
		(diameter 0)
		(color 0 0 0 0)
	)
	(junction
		(at 328.93 77.47)
		(diameter 0)
		(color 0 0 0 0)
	)
	(junction
		(at 127.635 76.2)
		(diameter 0)
		(color 0 0 0 0)
	)
	(bus_entry
		(at 238.125 210.185)
		(size -2.54 -2.54)
		(stroke
			(width 0)
			(type default)
		)
	)
	(bus_entry
		(at 64.77 215.9)
		(size -2.54 -2.54)
		(stroke
			(width 0)
			(type default)
		)
	)
	(bus_entry
		(at 94.615 210.82)
		(size -2.54 -2.54)
		(stroke
			(width 0)
			(type default)
		)
	)
	(bus_entry
		(at 60.96 82.55)
		(size -2.54 -2.54)
		(stroke
			(width 0)
			(type default)
		)
	)
	(bus_entry
		(at 64.77 191.77)
		(size -2.54 -2.54)
		(stroke
			(width 0)
			(type default)
		)
	)
	(bus_entry
		(at 160.02 82.55)
		(size 2.54 -2.54)
		(stroke
			(width 0)
			(type default)
		)
	)
	(bus_entry
		(at 94.615 186.69)
		(size -2.54 -2.54)
		(stroke
			(width 0)
			(type default)
		)
	)
	(bus_entry
		(at 311.785 198.755)
		(size 2.54 -2.54)
		(stroke
			(width 0)
			(type default)
		)
	)
	(bus_entry
		(at 238.125 201.295)
		(size -2.54 -2.54)
		(stroke
			(width 0)
			(type default)
		)
	)
	(bus_entry
		(at 60.96 85.09)
		(size -2.54 -2.54)
		(stroke
			(width 0)
			(type default)
		)
	)
	(bus_entry
		(at 311.785 207.645)
		(size 2.54 -2.54)
		(stroke
			(width 0)
			(type default)
		)
	)
	(bus_entry
		(at 76.835 189.23)
		(size -2.54 -2.54)
		(stroke
			(width 0)
			(type default)
		)
	)
	(bus_entry
		(at 267.97 205.105)
		(size -2.54 -2.54)
		(stroke
			(width 0)
			(type default)
		)
	)
	(bus_entry
		(at 160.02 85.09)
		(size 2.54 -2.54)
		(stroke
			(width 0)
			(type default)
		)
	)
	(bus_entry
		(at 76.835 213.36)
		(size -2.54 -2.54)
		(stroke
			(width 0)
			(type default)
		)
	)
	(bus_entry
		(at 250.19 207.645)
		(size -2.54 -2.54)
		(stroke
			(width 0)
			(type default)
		)
	)
	(bus_entry
		(at 267.97 196.215)
		(size -2.54 -2.54)
		(stroke
			(width 0)
			(type default)
		)
	)
	(bus_entry
		(at 250.19 198.755)
		(size -2.54 -2.54)
		(stroke
			(width 0)
			(type default)
		)
	)
	(wire
		(pts
			(xy 185.42 186.69) (xy 170.18 186.69)
		)
		(stroke
			(width 0)
			(type default)
		)
	)
	(wire
		(pts
			(xy 283.21 81.28) (xy 283.21 85.09)
		)
		(stroke
			(width 0)
			(type default)
		)
	)
	(wire
		(pts
			(xy 120.015 189.23) (xy 143.51 189.23)
		)
		(stroke
			(width 0)
			(type default)
		)
	)
	(wire
		(pts
			(xy 93.98 82.55) (xy 83.185 82.55)
		)
		(stroke
			(width 0)
			(type default)
		)
	)
	(wire
		(pts
			(xy 304.8 80.01) (xy 304.8 85.09)
		)
		(stroke
			(width 0)
			(type default)
		)
	)
	(wire
		(pts
			(xy 92.71 80.01) (xy 93.98 80.01)
		)
		(stroke
			(width 0)
			(type default)
		)
	)
	(bus
		(pts
			(xy 61.595 186.69) (xy 62.23 187.325)
		)
		(stroke
			(width 0)
			(type default)
		)
	)
	(wire
		(pts
			(xy 250.19 198.755) (xy 287.02 198.755)
		)
		(stroke
			(width 0)
			(type default)
		)
	)
	(bus
		(pts
			(xy 314.325 195.58) (xy 314.325 196.215)
		)
		(stroke
			(width 0)
			(type default)
		)
	)
	(bus
		(pts
			(xy 235.585 198.755) (xy 235.585 207.645)
		)
		(stroke
			(width 0)
			(type default)
		)
	)
	(wire
		(pts
			(xy 185.42 186.69) (xy 185.42 189.23)
		)
		(stroke
			(width 0)
			(type default)
		)
	)
	(wire
		(pts
			(xy 114.3 87.63) (xy 111.76 87.63)
		)
		(stroke
			(width 0)
			(type default)
		)
	)
	(wire
		(pts
			(xy 326.39 77.47) (xy 328.93 77.47)
		)
		(stroke
			(width 0)
			(type default)
		)
	)
	(wire
		(pts
			(xy 300.99 207.645) (xy 300.99 210.185)
		)
		(stroke
			(width 0)
			(type default)
		)
	)
	(wire
		(pts
			(xy 292.1 207.645) (xy 300.99 207.645)
		)
		(stroke
			(width 0)
			(type default)
		)
	)
	(bus
		(pts
			(xy 71.755 184.15) (xy 73.66 184.15)
		)
		(stroke
			(width 0)
			(type default)
		)
	)
	(wire
		(pts
			(xy 139.7 220.98) (xy 143.51 220.98)
		)
		(stroke
			(width 0)
			(type default)
		)
	)
	(polyline
		(pts
			(xy 143.51 234.315) (xy 167.64 234.315)
		)
		(stroke
			(width 0)
			(type dash)
		)
	)
	(wire
		(pts
			(xy 94.615 210.82) (xy 143.51 210.82)
		)
		(stroke
			(width 0)
			(type default)
		)
	)
	(wire
		(pts
			(xy 127.635 76.835) (xy 127.635 76.2)
		)
		(stroke
			(width 0)
			(type default)
		)
	)
	(wire
		(pts
			(xy 267.97 205.105) (xy 287.02 205.105)
		)
		(stroke
			(width 0)
			(type default)
		)
	)
	(wire
		(pts
			(xy 334.01 76.2) (xy 334.01 80.01)
		)
		(stroke
			(width 0)
			(type default)
		)
	)
	(polyline
		(pts
			(xy 12.065 134.62) (xy 407.67 134.62)
		)
		(stroke
			(width 0)
			(type default)
		)
	)
	(bus
		(pts
			(xy 165.1 78.105) (xy 163.195 78.105)
		)
		(stroke
			(width 0)
			(type default)
		)
	)
	(polyline
		(pts
			(xy 143.51 231.14) (xy 167.64 231.14)
		)
		(stroke
			(width 0)
			(type default)
		)
	)
	(wire
		(pts
			(xy 250.19 207.645) (xy 287.02 207.645)
		)
		(stroke
			(width 0)
			(type default)
		)
	)
	(wire
		(pts
			(xy 92.71 76.2) (xy 86.36 76.2)
		)
		(stroke
			(width 0)
			(type default)
		)
	)
	(bus
		(pts
			(xy 92.075 184.15) (xy 92.075 208.28)
		)
		(stroke
			(width 0)
			(type default)
		)
	)
	(wire
		(pts
			(xy 139.065 65.405) (xy 139.065 62.865)
		)
		(stroke
			(width 0)
			(type default)
		)
	)
	(wire
		(pts
			(xy 127.635 82.55) (xy 160.02 82.55)
		)
		(stroke
			(width 0)
			(type default)
		)
	)
	(bus
		(pts
			(xy 234.95 196.215) (xy 235.585 196.85)
		)
		(stroke
			(width 0)
			(type default)
		)
	)
	(wire
		(pts
			(xy 170.18 213.36) (xy 179.705 213.36)
		)
		(stroke
			(width 0)
			(type default)
		)
	)
	(bus
		(pts
			(xy 62.23 187.325) (xy 62.23 189.23)
		)
		(stroke
			(width 0)
			(type default)
		)
	)
	(wire
		(pts
			(xy 334.01 80.01) (xy 335.28 80.01)
		)
		(stroke
			(width 0)
			(type default)
		)
	)
	(wire
		(pts
			(xy 280.67 270.51) (xy 280.67 273.05)
		)
		(stroke
			(width 0)
			(type default)
		)
	)
	(wire
		(pts
			(xy 113.03 76.2) (xy 124.46 76.2)
		)
		(stroke
			(width 0)
			(type default)
		)
	)
	(bus
		(pts
			(xy 247.015 193.675) (xy 247.65 194.31)
		)
		(stroke
			(width 0)
			(type default)
		)
	)
	(wire
		(pts
			(xy 300.99 196.215) (xy 292.1 196.215)
		)
		(stroke
			(width 0)
			(type default)
		)
	)
	(wire
		(pts
			(xy 68.58 50.165) (xy 68.58 52.705)
		)
		(stroke
			(width 0)
			(type default)
		)
	)
	(bus
		(pts
			(xy 74.295 184.785) (xy 74.295 186.69)
		)
		(stroke
			(width 0)
			(type default)
		)
	)
	(wire
		(pts
			(xy 300.99 198.755) (xy 300.99 196.215)
		)
		(stroke
			(width 0)
			(type default)
		)
	)
	(wire
		(pts
			(xy 123.19 177.165) (xy 123.19 177.8)
		)
		(stroke
			(width 0)
			(type default)
		)
	)
	(wire
		(pts
			(xy 170.18 199.39) (xy 171.45 199.39)
		)
		(stroke
			(width 0)
			(type default)
		)
	)
	(bus
		(pts
			(xy 74.295 186.69) (xy 74.295 210.82)
		)
		(stroke
			(width 0)
			(type default)
		)
	)
	(wire
		(pts
			(xy 114.3 87.63) (xy 114.3 89.535)
		)
		(stroke
			(width 0)
			(type default)
		)
	)
	(wire
		(pts
			(xy 83.185 82.55) (xy 83.185 81.915)
		)
		(stroke
			(width 0)
			(type default)
		)
	)
	(wire
		(pts
			(xy 120.015 177.165) (xy 123.19 177.165)
		)
		(stroke
			(width 0)
			(type default)
		)
	)
	(wire
		(pts
			(xy 328.93 77.47) (xy 335.28 77.47)
		)
		(stroke
			(width 0)
			(type default)
		)
	)
	(wire
		(pts
			(xy 145.415 55.88) (xy 145.415 57.785)
		)
		(stroke
			(width 0)
			(type default)
		)
	)
	(wire
		(pts
			(xy 300.99 198.755) (xy 311.785 198.755)
		)
		(stroke
			(width 0)
			(type default)
		)
	)
	(bus
		(pts
			(xy 91.44 181.61) (xy 92.075 182.245)
		)
		(stroke
			(width 0)
			(type default)
		)
	)
	(bus
		(pts
			(xy 247.65 196.215) (xy 247.65 205.105)
		)
		(stroke
			(width 0)
			(type default)
		)
	)
	(wire
		(pts
			(xy 120.015 177.8) (xy 120.015 177.165)
		)
		(stroke
			(width 0)
			(type default)
		)
	)
	(wire
		(pts
			(xy 326.39 82.55) (xy 327.66 82.55)
		)
		(stroke
			(width 0)
			(type default)
		)
	)
	(wire
		(pts
			(xy 124.46 81.915) (xy 124.46 85.09)
		)
		(stroke
			(width 0)
			(type default)
		)
	)
	(wire
		(pts
			(xy 76.835 213.36) (xy 123.19 213.36)
		)
		(stroke
			(width 0)
			(type default)
		)
	)
	(wire
		(pts
			(xy 86.36 85.09) (xy 86.36 81.915)
		)
		(stroke
			(width 0)
			(type default)
		)
	)
	(wire
		(pts
			(xy 133.35 75.565) (xy 133.35 76.2)
		)
		(stroke
			(width 0)
			(type default)
		)
	)
	(wire
		(pts
			(xy 353.06 80.01) (xy 340.36 80.01)
		)
		(stroke
			(width 0)
			(type default)
		)
	)
	(polyline
		(pts
			(xy 167.64 247.015) (xy 143.51 247.015)
		)
		(stroke
			(width 0)
			(type default)
		)
	)
	(wire
		(pts
			(xy 238.125 201.295) (xy 287.02 201.295)
		)
		(stroke
			(width 0)
			(type default)
		)
	)
	(wire
		(pts
			(xy 185.42 210.82) (xy 170.18 210.82)
		)
		(stroke
			(width 0)
			(type default)
		)
	)
	(wire
		(pts
			(xy 326.39 80.01) (xy 334.01 80.01)
		)
		(stroke
			(width 0)
			(type default)
		)
	)
	(wire
		(pts
			(xy 139.065 65.405) (xy 145.415 65.405)
		)
		(stroke
			(width 0)
			(type default)
		)
	)
	(bus
		(pts
			(xy 92.075 182.245) (xy 92.075 184.15)
		)
		(stroke
			(width 0)
			(type default)
		)
	)
	(wire
		(pts
			(xy 139.7 196.85) (xy 139.7 220.98)
		)
		(stroke
			(width 0)
			(type default)
		)
	)
	(wire
		(pts
			(xy 60.96 82.55) (xy 83.185 82.55)
		)
		(stroke
			(width 0)
			(type default)
		)
	)
	(bus
		(pts
			(xy 235.585 196.85) (xy 235.585 198.755)
		)
		(stroke
			(width 0)
			(type default)
		)
	)
	(wire
		(pts
			(xy 111.76 82.55) (xy 127.635 82.55)
		)
		(stroke
			(width 0)
			(type default)
		)
	)
	(wire
		(pts
			(xy 124.46 76.835) (xy 124.46 76.2)
		)
		(stroke
			(width 0)
			(type default)
		)
	)
	(bus
		(pts
			(xy 316.865 194.945) (xy 314.96 194.945)
		)
		(stroke
			(width 0)
			(type default)
		)
	)
	(bus
		(pts
			(xy 265.43 193.675) (xy 265.43 202.565)
		)
		(stroke
			(width 0)
			(type default)
		)
	)
	(wire
		(pts
			(xy 86.36 85.09) (xy 93.98 85.09)
		)
		(stroke
			(width 0)
			(type default)
		)
	)
	(bus
		(pts
			(xy 162.56 78.74) (xy 162.56 80.01)
		)
		(stroke
			(width 0)
			(type default)
		)
	)
	(wire
		(pts
			(xy 171.45 223.52) (xy 171.45 224.79)
		)
		(stroke
			(width 0)
			(type default)
		)
	)
	(wire
		(pts
			(xy 328.93 76.2) (xy 328.93 77.47)
		)
		(stroke
			(width 0)
			(type default)
		)
	)
	(wire
		(pts
			(xy 81.915 50.165) (xy 81.915 52.705)
		)
		(stroke
			(width 0)
			(type default)
		)
	)
	(bus
		(pts
			(xy 62.23 189.23) (xy 62.23 213.36)
		)
		(stroke
			(width 0)
			(type default)
		)
	)
	(wire
		(pts
			(xy 123.19 182.88) (xy 123.19 213.36)
		)
		(stroke
			(width 0)
			(type default)
		)
	)
	(bus
		(pts
			(xy 314.96 194.945) (xy 314.325 195.58)
		)
		(stroke
			(width 0)
			(type default)
		)
	)
	(wire
		(pts
			(xy 304.8 80.01) (xy 306.07 80.01)
		)
		(stroke
			(width 0)
			(type default)
		)
	)
	(wire
		(pts
			(xy 120.015 175.26) (xy 120.015 177.165)
		)
		(stroke
			(width 0)
			(type default)
		)
	)
	(wire
		(pts
			(xy 299.72 77.47) (xy 306.07 77.47)
		)
		(stroke
			(width 0)
			(type default)
		)
	)
	(wire
		(pts
			(xy 170.18 223.52) (xy 171.45 223.52)
		)
		(stroke
			(width 0)
			(type default)
		)
	)
	(wire
		(pts
			(xy 111.76 80.01) (xy 113.03 80.01)
		)
		(stroke
			(width 0)
			(type default)
		)
	)
	(polyline
		(pts
			(xy 162.56 231.775) (xy 162.56 247.015)
		)
		(stroke
			(width 0)
			(type default)
		)
	)
	(wire
		(pts
			(xy 300.99 207.645) (xy 311.785 207.645)
		)
		(stroke
			(width 0)
			(type default)
		)
	)
	(wire
		(pts
			(xy 288.29 77.47) (xy 290.83 77.47)
		)
		(stroke
			(width 0)
			(type default)
		)
	)
	(bus
		(pts
			(xy 89.535 181.61) (xy 91.44 181.61)
		)
		(stroke
			(width 0)
			(type default)
		)
	)
	(wire
		(pts
			(xy 76.835 189.23) (xy 120.015 189.23)
		)
		(stroke
			(width 0)
			(type default)
		)
	)
	(wire
		(pts
			(xy 185.42 185.42) (xy 185.42 186.69)
		)
		(stroke
			(width 0)
			(type default)
		)
	)
	(polyline
		(pts
			(xy 143.51 231.14) (xy 143.51 247.015)
		)
		(stroke
			(width 0)
			(type default)
		)
	)
	(wire
		(pts
			(xy 300.99 201.295) (xy 292.1 201.295)
		)
		(stroke
			(width 0)
			(type default)
		)
	)
	(bus
		(pts
			(xy 162.56 80.01) (xy 162.56 82.55)
		)
		(stroke
			(width 0)
			(type default)
		)
	)
	(wire
		(pts
			(xy 83.185 76.2) (xy 86.36 76.2)
		)
		(stroke
			(width 0)
			(type default)
		)
	)
	(polyline
		(pts
			(xy 167.64 231.14) (xy 167.64 247.015)
		)
		(stroke
			(width 0)
			(type default)
		)
	)
	(wire
		(pts
			(xy 288.29 74.93) (xy 290.83 74.93)
		)
		(stroke
			(width 0)
			(type default)
		)
	)
	(bus
		(pts
			(xy 58.42 78.74) (xy 58.42 80.01)
		)
		(stroke
			(width 0)
			(type default)
		)
	)
	(bus
		(pts
			(xy 57.785 78.105) (xy 58.42 78.74)
		)
		(stroke
			(width 0)
			(type default)
		)
	)
	(wire
		(pts
			(xy 255.27 264.16) (xy 255.27 273.05)
		)
		(stroke
			(width 0)
			(type default)
		)
	)
	(wire
		(pts
			(xy 281.94 81.28) (xy 283.21 81.28)
		)
		(stroke
			(width 0)
			(type default)
		)
	)
	(bus
		(pts
			(xy 59.69 186.69) (xy 61.595 186.69)
		)
		(stroke
			(width 0)
			(type default)
		)
	)
	(wire
		(pts
			(xy 60.96 85.09) (xy 86.36 85.09)
		)
		(stroke
			(width 0)
			(type default)
		)
	)
	(wire
		(pts
			(xy 124.46 85.09) (xy 160.02 85.09)
		)
		(stroke
			(width 0)
			(type default)
		)
	)
	(wire
		(pts
			(xy 267.97 196.215) (xy 287.02 196.215)
		)
		(stroke
			(width 0)
			(type default)
		)
	)
	(wire
		(pts
			(xy 83.185 74.295) (xy 83.185 76.2)
		)
		(stroke
			(width 0)
			(type default)
		)
	)
	(bus
		(pts
			(xy 245.11 193.675) (xy 247.015 193.675)
		)
		(stroke
			(width 0)
			(type default)
		)
	)
	(wire
		(pts
			(xy 267.97 270.51) (xy 267.97 274.32)
		)
		(stroke
			(width 0)
			(type default)
		)
	)
	(wire
		(pts
			(xy 185.42 209.55) (xy 185.42 210.82)
		)
		(stroke
			(width 0)
			(type default)
		)
	)
	(bus
		(pts
			(xy 233.045 196.215) (xy 234.95 196.215)
		)
		(stroke
			(width 0)
			(type default)
		)
	)
	(wire
		(pts
			(xy 86.36 76.2) (xy 86.36 76.835)
		)
		(stroke
			(width 0)
			(type default)
		)
	)
	(polyline
		(pts
			(xy 143.51 240.665) (xy 167.64 240.665)
		)
		(stroke
			(width 0)
			(type default)
		)
	)
	(wire
		(pts
			(xy 238.125 210.185) (xy 287.02 210.185)
		)
		(stroke
			(width 0)
			(type default)
		)
	)
	(wire
		(pts
			(xy 124.46 76.2) (xy 127.635 76.2)
		)
		(stroke
			(width 0)
			(type default)
		)
	)
	(wire
		(pts
			(xy 185.42 210.82) (xy 185.42 213.36)
		)
		(stroke
			(width 0)
			(type default)
		)
	)
	(wire
		(pts
			(xy 143.51 199.39) (xy 141.605 199.39)
		)
		(stroke
			(width 0)
			(type default)
		)
	)
	(wire
		(pts
			(xy 340.36 77.47) (xy 353.06 77.47)
		)
		(stroke
			(width 0)
			(type default)
		)
	)
	(wire
		(pts
			(xy 185.42 218.44) (xy 185.42 220.345)
		)
		(stroke
			(width 0)
			(type default)
		)
	)
	(wire
		(pts
			(xy 80.01 50.165) (xy 81.915 50.165)
		)
		(stroke
			(width 0)
			(type default)
		)
	)
	(wire
		(pts
			(xy 179.705 189.23) (xy 170.18 189.23)
		)
		(stroke
			(width 0)
			(type default)
		)
	)
	(wire
		(pts
			(xy 185.42 194.31) (xy 185.42 196.215)
		)
		(stroke
			(width 0)
			(type default)
		)
	)
	(wire
		(pts
			(xy 141.605 199.39) (xy 141.605 223.52)
		)
		(stroke
			(width 0)
			(type default)
		)
	)
	(bus
		(pts
			(xy 247.65 194.31) (xy 247.65 196.215)
		)
		(stroke
			(width 0)
			(type default)
		)
	)
	(wire
		(pts
			(xy 300.99 210.185) (xy 292.1 210.185)
		)
		(stroke
			(width 0)
			(type default)
		)
	)
	(wire
		(pts
			(xy 94.615 186.69) (xy 143.51 186.69)
		)
		(stroke
			(width 0)
			(type default)
		)
	)
	(wire
		(pts
			(xy 83.185 76.835) (xy 83.185 76.2)
		)
		(stroke
			(width 0)
			(type default)
		)
	)
	(wire
		(pts
			(xy 281.94 77.47) (xy 283.21 77.47)
		)
		(stroke
			(width 0)
			(type default)
		)
	)
	(wire
		(pts
			(xy 171.45 199.39) (xy 171.45 200.66)
		)
		(stroke
			(width 0)
			(type default)
		)
	)
	(wire
		(pts
			(xy 135.89 223.52) (xy 141.605 223.52)
		)
		(stroke
			(width 0)
			(type default)
		)
	)
	(wire
		(pts
			(xy 92.71 87.63) (xy 93.98 87.63)
		)
		(stroke
			(width 0)
			(type default)
		)
	)
	(bus
		(pts
			(xy 265.43 191.77) (xy 265.43 193.675)
		)
		(stroke
			(width 0)
			(type default)
		)
	)
	(wire
		(pts
			(xy 133.35 76.2) (xy 134.62 76.2)
		)
		(stroke
			(width 0)
			(type default)
		)
	)
	(bus
		(pts
			(xy 73.66 184.15) (xy 74.295 184.785)
		)
		(stroke
			(width 0)
			(type default)
		)
	)
	(wire
		(pts
			(xy 299.72 83.82) (xy 299.72 85.09)
		)
		(stroke
			(width 0)
			(type default)
		)
	)
	(wire
		(pts
			(xy 261.62 264.16) (xy 261.62 273.05)
		)
		(stroke
			(width 0)
			(type default)
		)
	)
	(wire
		(pts
			(xy 123.19 213.36) (xy 143.51 213.36)
		)
		(stroke
			(width 0)
			(type default)
		)
	)
	(bus
		(pts
			(xy 58.42 80.01) (xy 58.42 82.55)
		)
		(stroke
			(width 0)
			(type default)
		)
	)
	(wire
		(pts
			(xy 292.1 198.755) (xy 300.99 198.755)
		)
		(stroke
			(width 0)
			(type default)
		)
	)
	(wire
		(pts
			(xy 111.76 85.09) (xy 124.46 85.09)
		)
		(stroke
			(width 0)
			(type default)
		)
	)
	(wire
		(pts
			(xy 327.66 82.55) (xy 327.66 85.09)
		)
		(stroke
			(width 0)
			(type default)
		)
	)
	(wire
		(pts
			(xy 141.605 223.52) (xy 143.51 223.52)
		)
		(stroke
			(width 0)
			(type default)
		)
	)
	(wire
		(pts
			(xy 273.05 74.93) (xy 283.21 74.93)
		)
		(stroke
			(width 0)
			(type default)
		)
	)
	(wire
		(pts
			(xy 64.77 191.77) (xy 143.51 191.77)
		)
		(stroke
			(width 0)
			(type default)
		)
	)
	(wire
		(pts
			(xy 92.71 76.2) (xy 92.71 80.01)
		)
		(stroke
			(width 0)
			(type default)
		)
	)
	(polyline
		(pts
			(xy 158.115 231.775) (xy 158.115 247.015)
		)
		(stroke
			(width 0)
			(type dash)
		)
	)
	(bus
		(pts
			(xy 163.195 78.105) (xy 162.56 78.74)
		)
		(stroke
			(width 0)
			(type default)
		)
	)
	(wire
		(pts
			(xy 274.32 270.51) (xy 274.32 273.05)
		)
		(stroke
			(width 0)
			(type default)
		)
	)
	(wire
		(pts
			(xy 120.015 182.88) (xy 120.015 189.23)
		)
		(stroke
			(width 0)
			(type default)
		)
	)
	(bus
		(pts
			(xy 314.325 196.215) (xy 314.325 205.105)
		)
		(stroke
			(width 0)
			(type default)
		)
	)
	(polyline
		(pts
			(xy 210.058 12.192) (xy 210.058 134.62)
		)
		(stroke
			(width 0)
			(type default)
		)
	)
	(wire
		(pts
			(xy 139.065 55.88) (xy 139.065 57.785)
		)
		(stroke
			(width 0)
			(type default)
		)
	)
	(wire
		(pts
			(xy 113.03 80.01) (xy 113.03 76.2)
		)
		(stroke
			(width 0)
			(type default)
		)
	)
	(wire
		(pts
			(xy 300.99 198.755) (xy 300.99 201.295)
		)
		(stroke
			(width 0)
			(type default)
		)
	)
	(wire
		(pts
			(xy 300.99 205.105) (xy 292.1 205.105)
		)
		(stroke
			(width 0)
			(type default)
		)
	)
	(wire
		(pts
			(xy 300.99 205.105) (xy 300.99 207.645)
		)
		(stroke
			(width 0)
			(type default)
		)
	)
	(wire
		(pts
			(xy 290.83 77.47) (xy 299.72 77.47)
		)
		(stroke
			(width 0)
			(type default)
		)
	)
	(wire
		(pts
			(xy 273.05 73.66) (xy 273.05 74.93)
		)
		(stroke
			(width 0)
			(type default)
		)
	)
	(polyline
		(pts
			(xy 143.51 237.49) (xy 167.64 237.49)
		)
		(stroke
			(width 0)
			(type default)
		)
	)
	(wire
		(pts
			(xy 127.635 81.915) (xy 127.635 82.55)
		)
		(stroke
			(width 0)
			(type default)
		)
	)
	(polyline
		(pts
			(xy 143.51 243.84) (xy 167.005 243.84)
		)
		(stroke
			(width 0)
			(type default)
		)
	)
	(wire
		(pts
			(xy 145.415 65.405) (xy 145.415 62.865)
		)
		(stroke
			(width 0)
			(type default)
		)
	)
	(wire
		(pts
			(xy 135.255 65.405) (xy 139.065 65.405)
		)
		(stroke
			(width 0)
			(type default)
		)
	)
	(wire
		(pts
			(xy 127.635 76.2) (xy 133.35 76.2)
		)
		(stroke
			(width 0)
			(type default)
		)
	)
	(bus
		(pts
			(xy 262.89 191.135) (xy 264.795 191.135)
		)
		(stroke
			(width 0)
			(type default)
		)
	)
	(wire
		(pts
			(xy 64.77 215.9) (xy 143.51 215.9)
		)
		(stroke
			(width 0)
			(type default)
		)
	)
	(wire
		(pts
			(xy 299.72 77.47) (xy 299.72 78.74)
		)
		(stroke
			(width 0)
			(type default)
		)
	)
	(bus
		(pts
			(xy 264.795 191.135) (xy 265.43 191.77)
		)
		(stroke
			(width 0)
			(type default)
		)
	)
	(bus
		(pts
			(xy 55.88 78.105) (xy 57.785 78.105)
		)
		(stroke
			(width 0)
			(type default)
		)
	)
	(wire
		(pts
			(xy 135.89 196.85) (xy 139.7 196.85)
		)
		(stroke
			(width 0)
			(type default)
		)
	)
	(wire
		(pts
			(xy 143.51 196.85) (xy 139.7 196.85)
		)
		(stroke
			(width 0)
			(type default)
		)
	)
	(wire
		(pts
			(xy 290.83 74.93) (xy 290.83 77.47)
		)
		(stroke
			(width 0)
			(type default)
		)
	)
	(label "FPGA_DDR.SCL"
		(at 60.96 82.55 0)
		(effects
			(font
				(size 1.27 1.27)
			)
			(justify left bottom)
		)
	)
	(label "PWR.SCL"
		(at 179.705 213.36 180)
		(effects
			(font
				(size 1.27 1.27)
			)
			(justify right bottom)
		)
	)
	(label "PWR.SDA"
		(at 261.62 264.16 270)
		(effects
			(font
				(size 1.27 1.27)
			)
			(justify right bottom)
		)
	)
	(label "FPGA_DDR.SCL"
		(at 267.97 205.105 0)
		(effects
			(font
				(size 1.27 1.27)
			)
			(justify left bottom)
		)
	)
	(label "FTDI.SDA"
		(at 64.77 191.77 0)
		(effects
			(font
				(size 1.27 1.27)
			)
			(justify left bottom)
		)
	)
	(label "DDR.SDA"
		(at 160.02 85.09 180)
		(effects
			(font
				(size 1.27 1.27)
			)
			(justify right bottom)
		)
	)
	(label "PWR.SDA"
		(at 179.705 189.23 180)
		(effects
			(font
				(size 1.27 1.27)
			)
			(justify right bottom)
		)
	)
	(label "PWR.SDA"
		(at 353.06 77.47 180)
		(effects
			(font
				(size 1.27 1.27)
			)
			(justify right bottom)
		)
	)
	(label "PWR.SDA"
		(at 311.15 198.755 180)
		(effects
			(font
				(size 1.27 1.27)
			)
			(justify right bottom)
		)
	)
	(label "FPGA_DDR.SDA"
		(at 267.97 196.215 0)
		(effects
			(font
				(size 1.27 1.27)
			)
			(justify left bottom)
		)
	)
	(label "FTDI.SCL"
		(at 238.125 210.185 0)
		(effects
			(font
				(size 1.27 1.27)
			)
			(justify left bottom)
		)
	)
	(label "DDR.SCL"
		(at 160.02 82.55 180)
		(effects
			(font
				(size 1.27 1.27)
			)
			(justify right bottom)
		)
	)
	(label "FPGA_DDR.SDA"
		(at 60.96 85.09 0)
		(effects
			(font
				(size 1.27 1.27)
			)
			(justify left bottom)
		)
	)
	(label "FPGA_PWR.SDA"
		(at 76.835 189.23 0)
		(effects
			(font
				(size 1.27 1.27)
			)
			(justify left bottom)
		)
	)
	(label "FTDI.SCL"
		(at 64.77 215.9 0)
		(effects
			(font
				(size 1.27 1.27)
			)
			(justify left bottom)
		)
	)
	(label "PWR.SCL"
		(at 353.06 80.01 180)
		(effects
			(font
				(size 1.27 1.27)
			)
			(justify right bottom)
		)
	)
	(label "FPGA_PWR.SCL"
		(at 250.19 207.645 0)
		(effects
			(font
				(size 1.27 1.27)
			)
			(justify left bottom)
		)
	)
	(label "FPGA_PWR.SCL"
		(at 76.835 213.36 0)
		(effects
			(font
				(size 1.27 1.27)
			)
			(justify left bottom)
		)
	)
	(label "PWR.SCL"
		(at 255.27 264.16 270)
		(effects
			(font
				(size 1.27 1.27)
			)
			(justify right bottom)
		)
	)
	(label "FPGA_PWR.SDA"
		(at 250.19 198.755 0)
		(effects
			(font
				(size 1.27 1.27)
			)
			(justify left bottom)
		)
	)
	(label "FTDI.SDA"
		(at 238.125 201.295 0)
		(effects
			(font
				(size 1.27 1.27)
			)
			(justify left bottom)
		)
	)
	(label "PWR.SCL"
		(at 311.785 207.645 180)
		(effects
			(font
				(size 1.27 1.27)
			)
			(justify right bottom)
		)
	)
	(label "FPGA_DDR.SCL"
		(at 94.615 210.82 0)
		(effects
			(font
				(size 1.27 1.27)
			)
			(justify left bottom)
		)
	)
	(label "FPGA_DDR.SDA"
		(at 94.615 186.69 0)
		(effects
			(font
				(size 1.27 1.27)
			)
			(justify left bottom)
		)
	)
	(global_label "IN1"
		(shape input)
		(at 135.89 196.85 180)
		(fields_autoplaced yes)
		(effects
			(font
				(size 1.27 1.27)
			)
			(justify right)
		)
		(property "Intersheetrefs" "${INTERSHEET_REFS}"
			(at 130.421 196.9294 0)
			(effects
				(font
					(size 1.27 1.27)
				)
				(justify right)
			)
		)
	)
	(global_label "IN2"
		(shape input)
		(at 280.67 270.51 90)
		(fields_autoplaced yes)
		(effects
			(font
				(size 1.27 1.27)
			)
			(justify left)
		)
		(property "Intersheetrefs" "${INTERSHEET_REFS}"
			(at 280.67 265.0342 90)
			(effects
				(font
					(size 1.27 1.27)
				)
				(justify left)
			)
		)
	)
	(global_label "VDDSPD"
		(shape input)
		(at 80.01 50.165 180)
		(fields_autoplaced yes)
		(effects
			(font
				(size 1.27 1.27)
			)
			(justify right)
		)
		(property "Intersheetrefs" "${INTERSHEET_REFS}"
			(at -155.575 445.77 0)
			(effects
				(font
					(size 1.27 1.27)
				)
			)
		)
	)
	(global_label "VDDSPD"
		(shape input)
		(at 134.62 76.2 0)
		(fields_autoplaced yes)
		(effects
			(font
				(size 1.27 1.27)
			)
			(justify left)
		)
		(property "Intersheetrefs" "${INTERSHEET_REFS}"
			(at -245.745 -151.765 0)
			(effects
				(font
					(size 1.27 1.27)
				)
			)
		)
	)
	(global_label "VDDSPD"
		(shape input)
		(at 135.255 65.405 180)
		(fields_autoplaced yes)
		(effects
			(font
				(size 1.27 1.27)
			)
			(justify right)
		)
		(property "Intersheetrefs" "${INTERSHEET_REFS}"
			(at 515.62 -162.56 0)
			(effects
				(font
					(size 1.27 1.27)
				)
				(justify left)
			)
		)
	)
	(global_label "IN2"
		(shape input)
		(at 135.89 223.52 180)
		(fields_autoplaced yes)
		(effects
			(font
				(size 1.27 1.27)
			)
			(justify right)
		)
		(property "Intersheetrefs" "${INTERSHEET_REFS}"
			(at 130.421 223.5994 0)
			(effects
				(font
					(size 1.27 1.27)
				)
				(justify right)
			)
		)
	)
	(global_label "IN1"
		(shape input)
		(at 274.32 270.51 90)
		(fields_autoplaced yes)
		(effects
			(font
				(size 1.27 1.27)
			)
			(justify left)
		)
		(property "Intersheetrefs" "${INTERSHEET_REFS}"
			(at 274.32 265.0342 90)
			(effects
				(font
					(size 1.27 1.27)
				)
				(justify left)
			)
		)
	)
	(hierarchical_label "FPGA_DDR{I^{2}C}"
		(shape bidirectional)
		(at 55.88 78.105 180)
		(effects
			(font
				(size 1.27 1.27)
			)
			(justify right)
		)
	)
	(hierarchical_label "PWR{I^{2}C}"
		(shape bidirectional)
		(at 316.865 194.945 0)
		(effects
			(font
				(size 1.27 1.27)
			)
			(justify left)
		)
	)
	(hierarchical_label "DDR{I^{2}C}"
		(shape bidirectional)
		(at 165.1 78.105 0)
		(effects
			(font
				(size 1.27 1.27)
			)
			(justify left)
		)
	)
	(hierarchical_label "FTDI{I^{2}C}"
		(shape bidirectional)
		(at 233.045 196.215 180)
		(effects
			(font
				(size 1.27 1.27)
			)
			(justify right)
		)
	)
	(hierarchical_label "FPGA_DDR{I^{2}C}"
		(shape bidirectional)
		(at 89.535 181.61 180)
		(effects
			(font
				(size 1.27 1.27)
			)
			(justify right)
		)
	)
	(hierarchical_label "FPGA_PWR{I^{2}C}"
		(shape bidirectional)
		(at 71.755 184.15 180)
		(effects
			(font
				(size 1.27 1.27)
			)
			(justify right)
		)
	)
	(hierarchical_label "FTDI{I^{2}C}"
		(shape bidirectional)
		(at 59.69 186.69 180)
		(effects
			(font
				(size 1.27 1.27)
			)
			(justify right)
		)
	)
	(hierarchical_label "FPGA_DDR{I^{2}C}"
		(shape bidirectional)
		(at 262.89 191.135 180)
		(effects
			(font
				(size 1.27 1.27)
			)
			(justify right)
		)
	)
	(hierarchical_label "FPGA_PWR{I^{2}C}"
		(shape bidirectional)
		(at 245.11 193.675 180)
		(effects
			(font
				(size 1.27 1.27)
			)
			(justify right)
		)
	)
	(symbol
		(lib_id "antmicroResistors0402:R_4k7_0402")
		(at 127.635 76.835 270)
		(unit 1)
		(exclude_from_sim no)
		(in_bom yes)
		(on_board yes)
		(dnp no)
		(property "Reference" "R125"
			(at 128.905 78.105 90)
			(effects
				(font
					(size 1.27 1.27)
				)
				(justify left)
			)
		)
		(property "Value" "R_4k7_0402"
			(at 114.935 97.155 0)
			(effects
				(font
					(size 1.27 1.27)
					(thickness 0.15)
				)
				(justify left bottom)
				(hide yes)
			)
		)
		(property "Footprint" "antmicro-footprints:R_0402_1005Metric"
			(at 112.395 97.155 0)
			(effects
				(font
					(size 1.27 1.27)
					(thickness 0.15)
				)
				(justify left bottom)
				(hide yes)
			)
		)
		(property "Datasheet" "https://www.bourns.com/docs/product-datasheets/cr.pdf"
			(at 109.855 97.155 0)
			(effects
				(font
					(size 1.27 1.27)
					(thickness 0.15)
				)
				(justify left bottom)
				(hide yes)
			)
		)
		(property "Description" ""
			(at 127.635 76.835 0)
			(effects
				(font
					(size 1.27 1.27)
				)
			)
		)
		(property "Manufacturer" "Bourns"
			(at 104.775 97.155 0)
			(effects
				(font
					(size 1.27 1.27)
					(thickness 0.15)
				)
				(justify left bottom)
				(hide yes)
			)
		)
		(property "MPN" "CR0402-FX-4701GLF"
			(at 107.315 97.155 0)
			(effects
				(font
					(size 1.27 1.27)
					(thickness 0.15)
				)
				(justify left bottom)
				(hide yes)
			)
		)
		(property "Val" "4k7"
			(at 128.905 80.645 90)
			(effects
				(font
					(size 1.27 1.27)
					(thickness 0.15)
				)
				(justify left)
			)
		)
		(property "License" "Apache-2.0"
			(at 102.235 97.155 0)
			(effects
				(font
					(size 1.27 1.27)
					(thickness 0.15)
				)
				(justify left bottom)
				(hide yes)
			)
		)
		(property "Author" "Antmicro"
			(at 99.695 97.155 0)
			(effects
				(font
					(size 1.27 1.27)
					(thickness 0.15)
				)
				(justify left bottom)
				(hide yes)
			)
		)
		(property "Tolerance" "1%"
			(at 117.475 97.155 0)
			(effects
				(font
					(size 1.27 1.27)
				)
				(justify left bottom)
				(hide yes)
			)
		)
		(pin "1"
		)
		(pin "2"
		)
		(instances
			(project "sodimm-ddr5-tester"
				(path ""
					(reference "R125")
					(unit 1)
				)
			)
		)
	)
	(symbol
		(lib_id "antmicroTestPoints:TP_1mm_SMD")
		(at 92.71 87.63 0)
		(mirror y)
		(unit 1)
		(exclude_from_sim no)
		(in_bom yes)
		(on_board yes)
		(dnp no)
		(property "Reference" "TP7"
			(at 91.44 90.17 0)
			(effects
				(font
					(size 1.27 1.27)
				)
				(justify left)
			)
		)
		(property "Value" "TP_1mm_SMD"
			(at 77.47 95.25 0)
			(effects
				(font
					(size 1.27 1.27)
					(thickness 0.15)
				)
				(justify left bottom)
				(hide yes)
			)
		)
		(property "Footprint" "antmicro-footprints:TP_SMD_1mm"
			(at 77.47 97.79 0)
			(effects
				(font
					(size 1.27 1.27)
					(thickness 0.15)
				)
				(justify left bottom)
				(hide yes)
			)
		)
		(property "Datasheet" ""
			(at 77.47 100.33 0)
			(effects
				(font
					(size 1.27 1.27)
					(thickness 0.15)
				)
				(justify left bottom)
				(hide yes)
			)
		)
		(property "Description" ""
			(at 92.71 87.63 0)
			(effects
				(font
					(size 1.27 1.27)
				)
			)
		)
		(property "MPN" ""
			(at 92.71 87.63 0)
			(effects
				(font
					(size 1.27 1.27)
				)
				(hide yes)
			)
		)
		(property "Manufacturer" ""
			(at 92.71 87.63 0)
			(effects
				(font
					(size 1.27 1.27)
				)
				(hide yes)
			)
		)
		(property "Author" "Antmicro"
			(at 77.47 102.87 0)
			(effects
				(font
					(size 1.27 1.27)
					(thickness 0.15)
				)
				(justify left bottom)
				(hide yes)
			)
		)
		(property "License" "Apache-2.0"
			(at 77.47 105.41 0)
			(effects
				(font
					(size 1.27 1.27)
					(thickness 0.15)
				)
				(justify left bottom)
				(hide yes)
			)
		)
		(pin "1"
		)
		(instances
			(project "sodimm-ddr5-tester"
				(path ""
					(reference "TP7")
					(unit 1)
				)
			)
		)
	)
	(symbol
		(lib_id "antmicroCapacitors0402:C_100n_0402")
		(at 81.915 52.705 90)
		(mirror x)
		(unit 1)
		(exclude_from_sim no)
		(in_bom yes)
		(on_board yes)
		(dnp no)
		(fields_autoplaced yes)
		(property "Reference" "C166"
			(at 84.2391 54.4207 90)
			(effects
				(font
					(size 1.27 1.27)
				)
				(justify right)
			)
		)
		(property "Value" "C_100n_0402"
			(at 92.075 73.025 0)
			(effects
				(font
					(size 1.27 1.27)
					(thickness 0.15)
				)
				(justify left bottom)
				(hide yes)
			)
		)
		(property "Footprint" "antmicro-footprints:C_0402_1005Metric"
			(at 94.615 73.025 0)
			(effects
				(font
					(size 1.27 1.27)
					(thickness 0.15)
				)
				(justify left bottom)
				(hide yes)
			)
		)
		(property "Datasheet" "https://www.murata.com/products/productdetail?partno=GRM155R61H104KE14%23"
			(at 97.155 73.025 0)
			(effects
				(font
					(size 1.27 1.27)
					(thickness 0.15)
				)
				(justify left bottom)
				(hide yes)
			)
		)
		(property "Description" ""
			(at 81.915 52.705 0)
			(effects
				(font
					(size 1.27 1.27)
				)
			)
		)
		(property "Manufacturer" "Murata"
			(at 102.235 73.025 0)
			(effects
				(font
					(size 1.27 1.27)
					(thickness 0.15)
				)
				(justify left bottom)
				(hide yes)
			)
		)
		(property "MPN" "GRM155R61H104KE14D"
			(at 99.695 73.025 0)
			(effects
				(font
					(size 1.27 1.27)
					(thickness 0.15)
				)
				(justify left bottom)
				(hide yes)
			)
		)
		(property "Val" "100n"
			(at 84.2391 56.951 90)
			(effects
				(font
					(size 1.27 1.27)
					(thickness 0.15)
				)
				(justify right)
			)
		)
		(property "License" "Apache-2.0"
			(at 104.775 73.025 0)
			(effects
				(font
					(size 1.27 1.27)
					(thickness 0.15)
				)
				(justify left bottom)
				(hide yes)
			)
		)
		(property "Author" "Antmicro"
			(at 107.315 73.025 0)
			(effects
				(font
					(size 1.27 1.27)
					(thickness 0.15)
				)
				(justify left bottom)
				(hide yes)
			)
		)
		(property "Voltage" "50V"
			(at 109.855 73.025 0)
			(effects
				(font
					(size 1.27 1.27)
				)
				(justify left bottom)
				(hide yes)
			)
		)
		(property "Dielectric" "X5R"
			(at 112.395 73.025 0)
			(effects
				(font
					(size 1.27 1.27)
				)
				(justify left bottom)
				(hide yes)
			)
		)
		(pin "1"
		)
		(pin "2"
		)
		(instances
			(project "sodimm-ddr5-tester"
				(path ""
					(reference "C166")
					(unit 1)
				)
			)
		)
	)
	(symbol
		(lib_id "antmicroResistors0402:R_0R_0402")
		(at 292.1 207.645 180)
		(unit 1)
		(exclude_from_sim no)
		(in_bom no)
		(on_board yes)
		(dnp yes)
		(property "Reference" "R178"
			(at 291.465 206.375 0)
			(effects
				(font
					(size 1.27 1.27)
				)
				(justify right)
			)
		)
		(property "Value" "R_0R_0402"
			(at 271.78 194.945 0)
			(effects
				(font
					(size 1.27 1.27)
					(thickness 0.15)
				)
				(justify left bottom)
				(hide yes)
			)
		)
		(property "Footprint" "antmicro-footprints:R_0402_1005Metric"
			(at 271.78 192.405 0)
			(effects
				(font
					(size 1.27 1.27)
					(thickness 0.15)
				)
				(justify left bottom)
				(hide yes)
			)
		)
		(property "Datasheet" "https://industrial.panasonic.com/cdbs/www-data/pdf/RDA0000/AOA0000C301.pdf"
			(at 271.78 189.865 0)
			(effects
				(font
					(size 1.27 1.27)
					(thickness 0.15)
				)
				(justify left bottom)
				(hide yes)
			)
		)
		(property "Description" ""
			(at 292.1 207.645 0)
			(effects
				(font
					(size 1.27 1.27)
				)
			)
		)
		(property "Manufacturer" "Panasonic"
			(at 271.78 184.785 0)
			(effects
				(font
					(size 1.27 1.27)
					(thickness 0.15)
				)
				(justify left bottom)
				(hide yes)
			)
		)
		(property "MPN" "ERJ2GE0R00X"
			(at 271.78 187.325 0)
			(effects
				(font
					(size 1.27 1.27)
					(thickness 0.15)
				)
				(justify left bottom)
				(hide yes)
			)
		)
		(property "Val" "0R"
			(at 284.48 206.375 0)
			(effects
				(font
					(size 1.27 1.27)
					(thickness 0.15)
				)
				(justify right)
			)
		)
		(property "License" "Apache-2.0"
			(at 271.78 182.245 0)
			(effects
				(font
					(size 1.27 1.27)
					(thickness 0.15)
				)
				(justify left bottom)
				(hide yes)
			)
		)
		(property "Author" "Antmicro"
			(at 271.78 179.705 0)
			(effects
				(font
					(size 1.27 1.27)
					(thickness 0.15)
				)
				(justify left bottom)
				(hide yes)
			)
		)
		(property "Tolerance" "~"
			(at 271.78 197.485 0)
			(effects
				(font
					(size 1.27 1.27)
				)
				(justify left bottom)
				(hide yes)
			)
		)
		(property "Current" "1A"
			(at 293.3699 205.105 90)
			(effects
				(font
					(size 1.27 1.27)
					(thickness 0.15)
				)
				(justify right)
				(hide yes)
			)
		)
		(pin "1"
		)
		(pin "2"
		)
		(instances
			(project "sodimm-ddr5-tester"
				(path ""
					(reference "R178")
					(unit 1)
				)
			)
		)
	)
	(symbol
		(lib_id "antmicroResistors0402:R_0R_0402")
		(at 340.36 77.47 180)
		(unit 1)
		(exclude_from_sim no)
		(in_bom yes)
		(on_board yes)
		(dnp no)
		(property "Reference" "R36"
			(at 335.788 75.692 0)
			(effects
				(font
					(size 1.27 1.27)
				)
				(justify right)
			)
		)
		(property "Value" "R_0R_0402"
			(at 320.04 64.77 0)
			(effects
				(font
					(size 1.27 1.27)
					(thickness 0.15)
				)
				(justify left bottom)
				(hide yes)
			)
		)
		(property "Footprint" "antmicro-footprints:R_0402_1005Metric"
			(at 320.04 62.23 0)
			(effects
				(font
					(size 1.27 1.27)
					(thickness 0.15)
				)
				(justify left bottom)
				(hide yes)
			)
		)
		(property "Datasheet" "https://industrial.panasonic.com/cdbs/www-data/pdf/RDA0000/AOA0000C301.pdf"
			(at 320.04 59.69 0)
			(effects
				(font
					(size 1.27 1.27)
					(thickness 0.15)
				)
				(justify left bottom)
				(hide yes)
			)
		)
		(property "Description" ""
			(at 340.36 77.47 0)
			(effects
				(font
					(size 1.27 1.27)
				)
			)
		)
		(property "Manufacturer" "Panasonic"
			(at 320.04 54.61 0)
			(effects
				(font
					(size 1.27 1.27)
					(thickness 0.15)
				)
				(justify left bottom)
				(hide yes)
			)
		)
		(property "MPN" "ERJ2GE0R00X"
			(at 320.04 57.15 0)
			(effects
				(font
					(size 1.27 1.27)
					(thickness 0.15)
				)
				(justify left bottom)
				(hide yes)
			)
		)
		(property "Val" "0R"
			(at 336.296 77.47 0)
			(effects
				(font
					(size 1.27 1.27)
					(thickness 0.15)
				)
				(justify right)
			)
		)
		(property "License" "Apache-2.0"
			(at 320.04 52.07 0)
			(effects
				(font
					(size 1.27 1.27)
					(thickness 0.15)
				)
				(justify left bottom)
				(hide yes)
			)
		)
		(property "Author" "Antmicro"
			(at 320.04 49.53 0)
			(effects
				(font
					(size 1.27 1.27)
					(thickness 0.15)
				)
				(justify left bottom)
				(hide yes)
			)
		)
		(property "Tolerance" "~"
			(at 320.04 67.31 0)
			(effects
				(font
					(size 1.27 1.27)
				)
				(justify left bottom)
				(hide yes)
			)
		)
		(property "Current" "1A"
			(at 341.6299 74.93 90)
			(effects
				(font
					(size 1.27 1.27)
					(thickness 0.15)
				)
				(justify right)
				(hide yes)
			)
		)
		(pin "1"
		)
		(pin "2"
		)
		(instances
			(project "sodimm-ddr5-tester"
				(path ""
					(reference "R36")
					(unit 1)
				)
			)
		)
	)
	(symbol
		(lib_id "antmicroResistors0402:R_4k7_0402")
		(at 120.015 177.8 270)
		(unit 1)
		(exclude_from_sim no)
		(in_bom yes)
		(on_board yes)
		(dnp no)
		(property "Reference" "R150"
			(at 118.745 179.07 90)
			(effects
				(font
					(size 1.27 1.27)
				)
				(justify right)
			)
		)
		(property "Value" "R_4k7_0402"
			(at 107.315 198.12 0)
			(effects
				(font
					(size 1.27 1.27)
					(thickness 0.15)
				)
				(justify left bottom)
				(hide yes)
			)
		)
		(property "Footprint" "antmicro-footprints:R_0402_1005Metric"
			(at 104.775 198.12 0)
			(effects
				(font
					(size 1.27 1.27)
					(thickness 0.15)
				)
				(justify left bottom)
				(hide yes)
			)
		)
		(property "Datasheet" "https://www.bourns.com/docs/product-datasheets/cr.pdf"
			(at 102.235 198.12 0)
			(effects
				(font
					(size 1.27 1.27)
					(thickness 0.15)
				)
				(justify left bottom)
				(hide yes)
			)
		)
		(property "Description" ""
			(at 120.015 177.8 0)
			(effects
				(font
					(size 1.27 1.27)
				)
			)
		)
		(property "Manufacturer" "Bourns"
			(at 97.155 198.12 0)
			(effects
				(font
					(size 1.27 1.27)
					(thickness 0.15)
				)
				(justify left bottom)
				(hide yes)
			)
		)
		(property "MPN" "CR0402-FX-4701GLF"
			(at 99.695 198.12 0)
			(effects
				(font
					(size 1.27 1.27)
					(thickness 0.15)
				)
				(justify left bottom)
				(hide yes)
			)
		)
		(property "Val" "4k7"
			(at 118.745 182.245 90)
			(effects
				(font
					(size 1.27 1.27)
					(thickness 0.15)
				)
				(justify right)
			)
		)
		(property "License" "Apache-2.0"
			(at 94.615 198.12 0)
			(effects
				(font
					(size 1.27 1.27)
					(thickness 0.15)
				)
				(justify left bottom)
				(hide yes)
			)
		)
		(property "Author" "Antmicro"
			(at 92.075 198.12 0)
			(effects
				(font
					(size 1.27 1.27)
					(thickness 0.15)
				)
				(justify left bottom)
				(hide yes)
			)
		)
		(property "Tolerance" "1%"
			(at 109.855 198.12 0)
			(effects
				(font
					(size 1.27 1.27)
				)
				(justify left bottom)
				(hide yes)
			)
		)
		(pin "1"
		)
		(pin "2"
		)
		(instances
			(project "sodimm-ddr5-tester"
				(path ""
					(reference "R150")
					(unit 1)
				)
			)
		)
	)
	(symbol
		(lib_id "antmicroCapacitors0402:C_100n_0402")
		(at 299.72 83.82 270)
		(mirror x)
		(unit 1)
		(exclude_from_sim no)
		(in_bom yes)
		(on_board yes)
		(dnp no)
		(fields_autoplaced yes)
		(property "Reference" "C239"
			(at 297.18 80.0035 90)
			(effects
				(font
					(size 1.27 1.27)
				)
				(justify right)
			)
		)
		(property "Value" "C_100n_0402"
			(at 289.56 63.5 0)
			(effects
				(font
					(size 1.27 1.27)
					(thickness 0.15)
				)
				(justify left bottom)
				(hide yes)
			)
		)
		(property "Footprint" "antmicro-footprints:C_0402_1005Metric"
			(at 287.02 63.5 0)
			(effects
				(font
					(size 1.27 1.27)
					(thickness 0.15)
				)
				(justify left bottom)
				(hide yes)
			)
		)
		(property "Datasheet" "https://www.murata.com/products/productdetail?partno=GRM155R61H104KE14%23"
			(at 284.48 63.5 0)
			(effects
				(font
					(size 1.27 1.27)
					(thickness 0.15)
				)
				(justify left bottom)
				(hide yes)
			)
		)
		(property "Description" ""
			(at 299.72 83.82 0)
			(effects
				(font
					(size 1.27 1.27)
				)
			)
		)
		(property "Manufacturer" "Murata"
			(at 279.4 63.5 0)
			(effects
				(font
					(size 1.27 1.27)
					(thickness 0.15)
				)
				(justify left bottom)
				(hide yes)
			)
		)
		(property "MPN" "GRM155R61H104KE14D"
			(at 281.94 63.5 0)
			(effects
				(font
					(size 1.27 1.27)
					(thickness 0.15)
				)
				(justify left bottom)
				(hide yes)
			)
		)
		(property "Val" "100n"
			(at 297.18 82.5435 90)
			(effects
				(font
					(size 1.27 1.27)
					(thickness 0.15)
				)
				(justify right)
			)
		)
		(property "License" "Apache-2.0"
			(at 276.86 63.5 0)
			(effects
				(font
					(size 1.27 1.27)
					(thickness 0.15)
				)
				(justify left bottom)
				(hide yes)
			)
		)
		(property "Author" "Antmicro"
			(at 274.32 63.5 0)
			(effects
				(font
					(size 1.27 1.27)
					(thickness 0.15)
				)
				(justify left bottom)
				(hide yes)
			)
		)
		(property "Voltage" "50V"
			(at 271.78 63.5 0)
			(effects
				(font
					(size 1.27 1.27)
				)
				(justify left bottom)
				(hide yes)
			)
		)
		(property "Dielectric" "X5R"
			(at 269.24 63.5 0)
			(effects
				(font
					(size 1.27 1.27)
				)
				(justify left bottom)
				(hide yes)
			)
		)
		(pin "1"
		)
		(pin "2"
		)
		(instances
			(project "sodimm-ddr5-tester"
				(path ""
					(reference "C239")
					(unit 1)
				)
			)
		)
	)
	(symbol
		(lib_id "antmicroResistors0402:R_4k7_0402")
		(at 124.46 76.835 270)
		(unit 1)
		(exclude_from_sim no)
		(in_bom yes)
		(on_board yes)
		(dnp no)
		(property "Reference" "R124"
			(at 123.19 78.105 90)
			(effects
				(font
					(size 1.27 1.27)
				)
				(justify right)
			)
		)
		(property "Value" "R_4k7_0402"
			(at 111.76 97.155 0)
			(effects
				(font
					(size 1.27 1.27)
					(thickness 0.15)
				)
				(justify left bottom)
				(hide yes)
			)
		)
		(property "Footprint" "antmicro-footprints:R_0402_1005Metric"
			(at 109.22 97.155 0)
			(effects
				(font
					(size 1.27 1.27)
					(thickness 0.15)
				)
				(justify left bottom)
				(hide yes)
			)
		)
		(property "Datasheet" "https://www.bourns.com/docs/product-datasheets/cr.pdf"
			(at 106.68 97.155 0)
			(effects
				(font
					(size 1.27 1.27)
					(thickness 0.15)
				)
				(justify left bottom)
				(hide yes)
			)
		)
		(property "Description" ""
			(at 124.46 76.835 0)
			(effects
				(font
					(size 1.27 1.27)
				)
			)
		)
		(property "Manufacturer" "Bourns"
			(at 101.6 97.155 0)
			(effects
				(font
					(size 1.27 1.27)
					(thickness 0.15)
				)
				(justify left bottom)
				(hide yes)
			)
		)
		(property "MPN" "CR0402-FX-4701GLF"
			(at 104.14 97.155 0)
			(effects
				(font
					(size 1.27 1.27)
					(thickness 0.15)
				)
				(justify left bottom)
				(hide yes)
			)
		)
		(property "Val" "4k7"
			(at 123.19 80.645 90)
			(effects
				(font
					(size 1.27 1.27)
					(thickness 0.15)
				)
				(justify right)
			)
		)
		(property "License" "Apache-2.0"
			(at 99.06 97.155 0)
			(effects
				(font
					(size 1.27 1.27)
					(thickness 0.15)
				)
				(justify left bottom)
				(hide yes)
			)
		)
		(property "Author" "Antmicro"
			(at 96.52 97.155 0)
			(effects
				(font
					(size 1.27 1.27)
					(thickness 0.15)
				)
				(justify left bottom)
				(hide yes)
			)
		)
		(property "Tolerance" "1%"
			(at 114.3 97.155 0)
			(effects
				(font
					(size 1.27 1.27)
				)
				(justify left bottom)
				(hide yes)
			)
		)
		(pin "1"
		)
		(pin "2"
		)
		(instances
			(project "sodimm-ddr5-tester"
				(path ""
					(reference "R124")
					(unit 1)
				)
			)
		)
	)
	(symbol
		(lib_id "antmicroTestPoints:TP_1mm_SMD")
		(at 281.94 77.47 180)
		(unit 1)
		(exclude_from_sim no)
		(in_bom yes)
		(on_board yes)
		(dnp no)
		(property "Reference" "TP67"
			(at 275.336 77.47 0)
			(effects
				(font
					(size 1.27 1.27)
				)
			)
		)
		(property "Value" "TP_1mm_SMD"
			(at 266.7 69.85 0)
			(effects
				(font
					(size 1.27 1.27)
					(thickness 0.15)
				)
				(justify left bottom)
				(hide yes)
			)
		)
		(property "Footprint" "antmicro-footprints:TP_SMD_1mm"
			(at 266.7 67.31 0)
			(effects
				(font
					(size 1.27 1.27)
					(thickness 0.15)
				)
				(justify left bottom)
				(hide yes)
			)
		)
		(property "Datasheet" ""
			(at 266.7 64.77 0)
			(effects
				(font
					(size 1.27 1.27)
					(thickness 0.15)
				)
				(justify left bottom)
				(hide yes)
			)
		)
		(property "Description" ""
			(at 281.94 77.47 0)
			(effects
				(font
					(size 1.27 1.27)
				)
			)
		)
		(property "MPN" ""
			(at 281.94 77.47 0)
			(effects
				(font
					(size 1.27 1.27)
				)
				(hide yes)
			)
		)
		(property "Manufacturer" ""
			(at 281.94 77.47 0)
			(effects
				(font
					(size 1.27 1.27)
				)
				(hide yes)
			)
		)
		(property "Author" "Antmicro"
			(at 266.7 62.23 0)
			(effects
				(font
					(size 1.27 1.27)
					(thickness 0.15)
				)
				(justify left bottom)
				(hide yes)
			)
		)
		(property "License" "Apache-2.0"
			(at 266.7 59.69 0)
			(effects
				(font
					(size 1.27 1.27)
					(thickness 0.15)
				)
				(justify left bottom)
				(hide yes)
			)
		)
		(pin "1"
		)
		(instances
			(project "sodimm-ddr5-tester"
				(path ""
					(reference "TP67")
					(unit 1)
				)
			)
		)
	)
	(symbol
		(lib_id "antmicroResistors0402:R_0R_0402")
		(at 292.1 201.295 180)
		(unit 1)
		(exclude_from_sim no)
		(in_bom no)
		(on_board yes)
		(dnp yes)
		(property "Reference" "R176"
			(at 291.465 200.025 0)
			(effects
				(font
					(size 1.27 1.27)
				)
				(justify right)
			)
		)
		(property "Value" "R_0R_0402"
			(at 271.78 188.595 0)
			(effects
				(font
					(size 1.27 1.27)
					(thickness 0.15)
				)
				(justify left bottom)
				(hide yes)
			)
		)
		(property "Footprint" "antmicro-footprints:R_0402_1005Metric"
			(at 271.78 186.055 0)
			(effects
				(font
					(size 1.27 1.27)
					(thickness 0.15)
				)
				(justify left bottom)
				(hide yes)
			)
		)
		(property "Datasheet" "https://industrial.panasonic.com/cdbs/www-data/pdf/RDA0000/AOA0000C301.pdf"
			(at 271.78 183.515 0)
			(effects
				(font
					(size 1.27 1.27)
					(thickness 0.15)
				)
				(justify left bottom)
				(hide yes)
			)
		)
		(property "Description" ""
			(at 292.1 201.295 0)
			(effects
				(font
					(size 1.27 1.27)
				)
			)
		)
		(property "Manufacturer" "Panasonic"
			(at 271.78 178.435 0)
			(effects
				(font
					(size 1.27 1.27)
					(thickness 0.15)
				)
				(justify left bottom)
				(hide yes)
			)
		)
		(property "MPN" "ERJ2GE0R00X"
			(at 271.78 180.975 0)
			(effects
				(font
					(size 1.27 1.27)
					(thickness 0.15)
				)
				(justify left bottom)
				(hide yes)
			)
		)
		(property "Val" "0R"
			(at 284.48 200.025 0)
			(effects
				(font
					(size 1.27 1.27)
					(thickness 0.15)
				)
				(justify right)
			)
		)
		(property "License" "Apache-2.0"
			(at 271.78 175.895 0)
			(effects
				(font
					(size 1.27 1.27)
					(thickness 0.15)
				)
				(justify left bottom)
				(hide yes)
			)
		)
		(property "Author" "Antmicro"
			(at 271.78 173.355 0)
			(effects
				(font
					(size 1.27 1.27)
					(thickness 0.15)
				)
				(justify left bottom)
				(hide yes)
			)
		)
		(property "Tolerance" "~"
			(at 271.78 191.135 0)
			(effects
				(font
					(size 1.27 1.27)
				)
				(justify left bottom)
				(hide yes)
			)
		)
		(property "Current" "1A"
			(at 293.3699 198.755 90)
			(effects
				(font
					(size 1.27 1.27)
					(thickness 0.15)
				)
				(justify right)
				(hide yes)
			)
		)
		(pin "1"
		)
		(pin "2"
		)
		(instances
			(project "sodimm-ddr5-tester"
				(path ""
					(reference "R176")
					(unit 1)
				)
			)
		)
	)
	(symbol
		(lib_id "antmicropower:+3V3_AON")
		(at 185.42 185.42 0)
		(mirror y)
		(unit 1)
		(exclude_from_sim no)
		(in_bom yes)
		(on_board yes)
		(dnp no)
		(fields_autoplaced yes)
		(property "Reference" "#PWR0441"
			(at 185.42 189.23 0)
			(effects
				(font
					(size 1.27 1.27)
				)
				(hide yes)
			)
		)
		(property "Value" "+3V3_AON"
			(at 185.42 179.705 0)
			(effects
				(font
					(size 1.27 1.27)
				)
			)
		)
		(property "Footprint" ""
			(at 185.42 185.42 0)
			(effects
				(font
					(size 1.27 1.27)
				)
				(hide yes)
			)
		)
		(property "Datasheet" ""
			(at 185.42 185.42 0)
			(effects
				(font
					(size 1.27 1.27)
				)
				(hide yes)
			)
		)
		(property "Description" ""
			(at 185.42 185.42 0)
			(effects
				(font
					(size 1.27 1.27)
				)
			)
		)
		(pin "1"
		)
		(instances
			(project "sodimm-ddr5-tester"
				(path ""
					(reference "#PWR0441")
					(unit 1)
				)
			)
		)
	)
	(symbol
		(lib_id "antmicropower:GND")
		(at 185.42 196.215 0)
		(mirror y)
		(unit 1)
		(exclude_from_sim no)
		(in_bom yes)
		(on_board yes)
		(dnp no)
		(fields_autoplaced yes)
		(property "Reference" "#PWR0437"
			(at 185.42 202.565 0)
			(effects
				(font
					(size 1.27 1.27)
				)
				(hide yes)
			)
		)
		(property "Value" "GND"
			(at 187.96 197.485 0)
			(effects
				(font
					(size 1.27 1.27)
					(thickness 0.15)
				)
				(justify right)
			)
		)
		(property "Footprint" ""
			(at 176.53 203.835 0)
			(effects
				(font
					(size 1.27 1.27)
					(thickness 0.15)
				)
				(justify left bottom)
				(hide yes)
			)
		)
		(property "Datasheet" ""
			(at 176.53 208.915 0)
			(effects
				(font
					(size 1.27 1.27)
					(thickness 0.15)
				)
				(justify left bottom)
				(hide yes)
			)
		)
		(property "Description" ""
			(at 176.53 211.455 0)
			(effects
				(font
					(size 1.27 1.27)
				)
				(justify left bottom)
				(hide yes)
			)
		)
		(property "Author" "Antmicro"
			(at 176.53 203.835 0)
			(effects
				(font
					(size 1.27 1.27)
					(thickness 0.15)
				)
				(justify left bottom)
				(hide yes)
			)
		)
		(property "License" "Apache-2.0"
			(at 176.53 206.375 0)
			(effects
				(font
					(size 1.27 1.27)
					(thickness 0.15)
				)
				(justify left bottom)
				(hide yes)
			)
		)
		(pin "1"
		)
		(instances
			(project "sodimm-ddr5-tester"
				(path ""
					(reference "#PWR0437")
					(unit 1)
				)
			)
		)
	)
	(symbol
		(lib_id "antmicroTestPoints:TP_1mm_SMD")
		(at 328.93 76.2 90)
		(unit 1)
		(exclude_from_sim no)
		(in_bom yes)
		(on_board yes)
		(dnp no)
		(property "Reference" "TP69"
			(at 328.93 71.2272 90)
			(effects
				(font
					(size 1.27 1.27)
				)
			)
		)
		(property "Value" "TP_1mm_SMD"
			(at 336.55 60.96 0)
			(effects
				(font
					(size 1.27 1.27)
					(thickness 0.15)
				)
				(justify left bottom)
				(hide yes)
			)
		)
		(property "Footprint" "antmicro-footprints:TP_SMD_1mm"
			(at 339.09 60.96 0)
			(effects
				(font
					(size 1.27 1.27)
					(thickness 0.15)
				)
				(justify left bottom)
				(hide yes)
			)
		)
		(property "Datasheet" ""
			(at 341.63 60.96 0)
			(effects
				(font
					(size 1.27 1.27)
					(thickness 0.15)
				)
				(justify left bottom)
				(hide yes)
			)
		)
		(property "Description" ""
			(at 328.93 76.2 0)
			(effects
				(font
					(size 1.27 1.27)
				)
			)
		)
		(property "MPN" ""
			(at 328.93 76.2 0)
			(effects
				(font
					(size 1.27 1.27)
				)
				(hide yes)
			)
		)
		(property "Manufacturer" ""
			(at 328.93 76.2 0)
			(effects
				(font
					(size 1.27 1.27)
				)
				(hide yes)
			)
		)
		(property "Author" "Antmicro"
			(at 344.17 60.96 0)
			(effects
				(font
					(size 1.27 1.27)
					(thickness 0.15)
				)
				(justify left bottom)
				(hide yes)
			)
		)
		(property "License" "Apache-2.0"
			(at 346.71 60.96 0)
			(effects
				(font
					(size 1.27 1.27)
					(thickness 0.15)
				)
				(justify left bottom)
				(hide yes)
			)
		)
		(pin "1"
		)
		(instances
			(project "sodimm-ddr5-tester"
				(path ""
					(reference "TP69")
					(unit 1)
				)
			)
		)
	)
	(symbol
		(lib_id "antmicropower:+3V3")
		(at 120.015 175.26 0)
		(unit 1)
		(exclude_from_sim no)
		(in_bom yes)
		(on_board yes)
		(dnp no)
		(fields_autoplaced yes)
		(property "Reference" "#PWR0442"
			(at 120.015 179.07 0)
			(effects
				(font
					(size 1.27 1.27)
				)
				(hide yes)
			)
		)
		(property "Value" "+3V3"
			(at 116.84 172.72 0)
			(effects
				(font
					(size 1.27 1.27)
					(thickness 0.15)
				)
				(justify left bottom)
			)
		)
		(property "Footprint" ""
			(at 135.255 182.88 0)
			(effects
				(font
					(size 1.27 1.27)
					(thickness 0.15)
				)
				(justify left bottom)
				(hide yes)
			)
		)
		(property "Datasheet" ""
			(at 135.255 185.42 0)
			(effects
				(font
					(size 1.27 1.27)
					(thickness 0.15)
				)
				(justify left bottom)
				(hide yes)
			)
		)
		(property "Description" ""
			(at 120.015 175.26 0)
			(effects
				(font
					(size 1.27 1.27)
				)
			)
		)
		(property "Author" "Antmicro"
			(at 135.255 177.8 0)
			(effects
				(font
					(size 1.27 1.27)
					(thickness 0.15)
				)
				(justify left bottom)
				(hide yes)
			)
		)
		(property "License" "Apache-2.0"
			(at 135.255 180.34 0)
			(effects
				(font
					(size 1.27 1.27)
					(thickness 0.15)
				)
				(justify left bottom)
				(hide yes)
			)
		)
		(pin "1"
		)
		(instances
			(project "sodimm-ddr5-tester"
				(path ""
					(reference "#PWR0442")
					(unit 1)
				)
			)
		)
	)
	(symbol
		(lib_id "antmicroCapacitors0402:C_100n_0402")
		(at 185.42 218.44 270)
		(mirror x)
		(unit 1)
		(exclude_from_sim no)
		(in_bom yes)
		(on_board yes)
		(dnp no)
		(fields_autoplaced yes)
		(property "Reference" "C197"
			(at 182.88 214.6235 90)
			(effects
				(font
					(size 1.27 1.27)
				)
				(justify right)
			)
		)
		(property "Value" "C_100n_0402"
			(at 175.26 198.12 0)
			(effects
				(font
					(size 1.27 1.27)
					(thickness 0.15)
				)
				(justify left bottom)
				(hide yes)
			)
		)
		(property "Footprint" "antmicro-footprints:C_0402_1005Metric"
			(at 172.72 198.12 0)
			(effects
				(font
					(size 1.27 1.27)
					(thickness 0.15)
				)
				(justify left bottom)
				(hide yes)
			)
		)
		(property "Datasheet" "https://www.murata.com/products/productdetail?partno=GRM155R61H104KE14%23"
			(at 170.18 198.12 0)
			(effects
				(font
					(size 1.27 1.27)
					(thickness 0.15)
				)
				(justify left bottom)
				(hide yes)
			)
		)
		(property "Description" ""
			(at 185.42 218.44 0)
			(effects
				(font
					(size 1.27 1.27)
				)
			)
		)
		(property "Manufacturer" "Murata"
			(at 165.1 198.12 0)
			(effects
				(font
					(size 1.27 1.27)
					(thickness 0.15)
				)
				(justify left bottom)
				(hide yes)
			)
		)
		(property "MPN" "GRM155R61H104KE14D"
			(at 167.64 198.12 0)
			(effects
				(font
					(size 1.27 1.27)
					(thickness 0.15)
				)
				(justify left bottom)
				(hide yes)
			)
		)
		(property "Val" "100n"
			(at 182.88 217.1635 90)
			(effects
				(font
					(size 1.27 1.27)
					(thickness 0.15)
				)
				(justify right)
			)
		)
		(property "License" "Apache-2.0"
			(at 162.56 198.12 0)
			(effects
				(font
					(size 1.27 1.27)
					(thickness 0.15)
				)
				(justify left bottom)
				(hide yes)
			)
		)
		(property "Author" "Antmicro"
			(at 160.02 198.12 0)
			(effects
				(font
					(size 1.27 1.27)
					(thickness 0.15)
				)
				(justify left bottom)
				(hide yes)
			)
		)
		(property "Voltage" "50V"
			(at 157.48 198.12 0)
			(effects
				(font
					(size 1.27 1.27)
				)
				(justify left bottom)
				(hide yes)
			)
		)
		(property "Dielectric" "X5R"
			(at 154.94 198.12 0)
			(effects
				(font
					(size 1.27 1.27)
				)
				(justify left bottom)
				(hide yes)
			)
		)
		(pin "1"
		)
		(pin "2"
		)
		(instances
			(project "sodimm-ddr5-tester"
				(path ""
					(reference "C197")
					(unit 1)
				)
			)
		)
	)
	(symbol
		(lib_id "antmicroTestPoints:TP_1mm_SMD")
		(at 280.67 273.05 270)
		(unit 1)
		(exclude_from_sim no)
		(in_bom yes)
		(on_board yes)
		(dnp no)
		(property "Reference" "TP41"
			(at 280.67 278.0228 90)
			(effects
				(font
					(size 1.27 1.27)
				)
			)
		)
		(property "Value" "TP_1mm_SMD"
			(at 273.05 288.29 0)
			(effects
				(font
					(size 1.27 1.27)
					(thickness 0.15)
				)
				(justify left bottom)
				(hide yes)
			)
		)
		(property "Footprint" "antmicro-footprints:TP_SMD_1mm"
			(at 270.51 288.29 0)
			(effects
				(font
					(size 1.27 1.27)
					(thickness 0.15)
				)
				(justify left bottom)
				(hide yes)
			)
		)
		(property "Datasheet" ""
			(at 267.97 288.29 0)
			(effects
				(font
					(size 1.27 1.27)
					(thickness 0.15)
				)
				(justify left bottom)
				(hide yes)
			)
		)
		(property "Description" ""
			(at 280.67 273.05 0)
			(effects
				(font
					(size 1.27 1.27)
				)
			)
		)
		(property "MPN" ""
			(at 280.67 273.05 0)
			(effects
				(font
					(size 1.27 1.27)
				)
				(hide yes)
			)
		)
		(property "Manufacturer" ""
			(at 280.67 273.05 0)
			(effects
				(font
					(size 1.27 1.27)
				)
				(hide yes)
			)
		)
		(property "Author" "Antmicro"
			(at 265.43 288.29 0)
			(effects
				(font
					(size 1.27 1.27)
					(thickness 0.15)
				)
				(justify left bottom)
				(hide yes)
			)
		)
		(property "License" "Apache-2.0"
			(at 262.89 288.29 0)
			(effects
				(font
					(size 1.27 1.27)
					(thickness 0.15)
				)
				(justify left bottom)
				(hide yes)
			)
		)
		(pin "1"
		)
		(instances
			(project "sodimm-ddr5-tester"
				(path ""
					(reference "TP41")
					(unit 1)
				)
			)
		)
	)
	(symbol
		(lib_id "antmicroResistors0402:R_0R_0402")
		(at 145.415 62.865 270)
		(mirror x)
		(unit 1)
		(exclude_from_sim no)
		(in_bom yes)
		(on_board yes)
		(dnp no)
		(fields_autoplaced yes)
		(property "Reference" "R127"
			(at 147.066 59.4944 90)
			(effects
				(font
					(size 1.27 1.27)
					(thickness 0.15)
				)
				(justify left)
			)
		)
		(property "Value" "R_0R_0402"
			(at 132.715 42.545 0)
			(effects
				(font
					(size 1.27 1.27)
					(thickness 0.15)
				)
				(justify left bottom)
				(hide yes)
			)
		)
		(property "Footprint" "antmicro-footprints:R_0402_1005Metric"
			(at 130.175 42.545 0)
			(effects
				(font
					(size 1.27 1.27)
					(thickness 0.15)
				)
				(justify left bottom)
				(hide yes)
			)
		)
		(property "Datasheet" "https://industrial.panasonic.com/cdbs/www-data/pdf/RDA0000/AOA0000C301.pdf"
			(at 127.635 42.545 0)
			(effects
				(font
					(size 1.27 1.27)
					(thickness 0.15)
				)
				(justify left bottom)
				(hide yes)
			)
		)
		(property "Description" ""
			(at 145.415 62.865 0)
			(effects
				(font
					(size 1.27 1.27)
				)
			)
		)
		(property "MPN" "ERJ2GE0R00X"
			(at 125.095 42.545 0)
			(effects
				(font
					(size 1.27 1.27)
					(thickness 0.15)
				)
				(justify left bottom)
				(hide yes)
			)
		)
		(property "Manufacturer" "Panasonic"
			(at 122.555 42.545 0)
			(effects
				(font
					(size 1.27 1.27)
					(thickness 0.15)
				)
				(justify left bottom)
				(hide yes)
			)
		)
		(property "License" "Apache-2.0"
			(at 120.015 42.545 0)
			(effects
				(font
					(size 1.27 1.27)
					(thickness 0.15)
				)
				(justify left bottom)
				(hide yes)
			)
		)
		(property "Author" "Antmicro"
			(at 117.475 42.545 0)
			(effects
				(font
					(size 1.27 1.27)
					(thickness 0.15)
				)
				(justify left bottom)
				(hide yes)
			)
		)
		(property "Val" "0R"
			(at 147.066 62.0181 90)
			(effects
				(font
					(size 1.27 1.27)
					(thickness 0.15)
				)
				(justify left)
			)
		)
		(property "Tolerance" "~"
			(at 135.255 42.545 0)
			(effects
				(font
					(size 1.27 1.27)
				)
				(justify left bottom)
				(hide yes)
			)
		)
		(property "Current" "1A"
			(at 114.935 42.545 0)
			(effects
				(font
					(size 1.27 1.27)
					(thickness 0.15)
				)
				(justify left bottom)
				(hide yes)
			)
		)
		(pin "1"
		)
		(pin "2"
		)
		(instances
			(project "sodimm-ddr5-tester"
				(path ""
					(reference "R127")
					(unit 1)
				)
			)
		)
	)
	(symbol
		(lib_id "antmicroTestPoints:TP_1mm_SMD")
		(at 255.27 273.05 270)
		(unit 1)
		(exclude_from_sim no)
		(in_bom yes)
		(on_board yes)
		(dnp no)
		(property "Reference" "TP37"
			(at 255.27 278.0228 90)
			(effects
				(font
					(size 1.27 1.27)
				)
			)
		)
		(property "Value" "TP_1mm_SMD"
			(at 247.65 288.29 0)
			(effects
				(font
					(size 1.27 1.27)
					(thickness 0.15)
				)
				(justify left bottom)
				(hide yes)
			)
		)
		(property "Footprint" "antmicro-footprints:TP_SMD_1mm"
			(at 245.11 288.29 0)
			(effects
				(font
					(size 1.27 1.27)
					(thickness 0.15)
				)
				(justify left bottom)
				(hide yes)
			)
		)
		(property "Datasheet" ""
			(at 242.57 288.29 0)
			(effects
				(font
					(size 1.27 1.27)
					(thickness 0.15)
				)
				(justify left bottom)
				(hide yes)
			)
		)
		(property "Description" ""
			(at 255.27 273.05 0)
			(effects
				(font
					(size 1.27 1.27)
				)
			)
		)
		(property "MPN" ""
			(at 255.27 273.05 0)
			(effects
				(font
					(size 1.27 1.27)
				)
				(hide yes)
			)
		)
		(property "Manufacturer" ""
			(at 255.27 273.05 0)
			(effects
				(font
					(size 1.27 1.27)
				)
				(hide yes)
			)
		)
		(property "Author" "Antmicro"
			(at 240.03 288.29 0)
			(effects
				(font
					(size 1.27 1.27)
					(thickness 0.15)
				)
				(justify left bottom)
				(hide yes)
			)
		)
		(property "License" "Apache-2.0"
			(at 237.49 288.29 0)
			(effects
				(font
					(size 1.27 1.27)
					(thickness 0.15)
				)
				(justify left bottom)
				(hide yes)
			)
		)
		(pin "1"
		)
		(instances
			(project "sodimm-ddr5-tester"
				(path ""
					(reference "TP37")
					(unit 1)
				)
			)
		)
	)
	(symbol
		(lib_id "antmicroResistors0402:R_0R_0402")
		(at 292.1 196.215 180)
		(unit 1)
		(exclude_from_sim no)
		(in_bom no)
		(on_board yes)
		(dnp yes)
		(property "Reference" "R174"
			(at 291.465 194.945 0)
			(effects
				(font
					(size 1.27 1.27)
				)
				(justify right)
			)
		)
		(property "Value" "R_0R_0402"
			(at 271.78 183.515 0)
			(effects
				(font
					(size 1.27 1.27)
					(thickness 0.15)
				)
				(justify left bottom)
				(hide yes)
			)
		)
		(property "Footprint" "antmicro-footprints:R_0402_1005Metric"
			(at 271.78 180.975 0)
			(effects
				(font
					(size 1.27 1.27)
					(thickness 0.15)
				)
				(justify left bottom)
				(hide yes)
			)
		)
		(property "Datasheet" "https://industrial.panasonic.com/cdbs/www-data/pdf/RDA0000/AOA0000C301.pdf"
			(at 271.78 178.435 0)
			(effects
				(font
					(size 1.27 1.27)
					(thickness 0.15)
				)
				(justify left bottom)
				(hide yes)
			)
		)
		(property "Description" ""
			(at 292.1 196.215 0)
			(effects
				(font
					(size 1.27 1.27)
				)
			)
		)
		(property "Manufacturer" "Panasonic"
			(at 271.78 173.355 0)
			(effects
				(font
					(size 1.27 1.27)
					(thickness 0.15)
				)
				(justify left bottom)
				(hide yes)
			)
		)
		(property "MPN" "ERJ2GE0R00X"
			(at 271.78 175.895 0)
			(effects
				(font
					(size 1.27 1.27)
					(thickness 0.15)
				)
				(justify left bottom)
				(hide yes)
			)
		)
		(property "Val" "0R"
			(at 284.48 194.945 0)
			(effects
				(font
					(size 1.27 1.27)
					(thickness 0.15)
				)
				(justify right)
			)
		)
		(property "License" "Apache-2.0"
			(at 271.78 170.815 0)
			(effects
				(font
					(size 1.27 1.27)
					(thickness 0.15)
				)
				(justify left bottom)
				(hide yes)
			)
		)
		(property "Author" "Antmicro"
			(at 271.78 168.275 0)
			(effects
				(font
					(size 1.27 1.27)
					(thickness 0.15)
				)
				(justify left bottom)
				(hide yes)
			)
		)
		(property "Tolerance" "~"
			(at 271.78 186.055 0)
			(effects
				(font
					(size 1.27 1.27)
				)
				(justify left bottom)
				(hide yes)
			)
		)
		(property "Current" "1A"
			(at 293.3699 193.675 90)
			(effects
				(font
					(size 1.27 1.27)
					(thickness 0.15)
				)
				(justify right)
				(hide yes)
			)
		)
		(pin "1"
		)
		(pin "2"
		)
		(instances
			(project "sodimm-ddr5-tester"
				(path ""
					(reference "R174")
					(unit 1)
				)
			)
		)
	)
	(symbol
		(lib_id "antmicropower:GND")
		(at 171.45 200.66 0)
		(unit 1)
		(exclude_from_sim no)
		(in_bom yes)
		(on_board yes)
		(dnp no)
		(property "Reference" "#PWR0436"
			(at 171.45 207.01 0)
			(effects
				(font
					(size 1.27 1.27)
				)
				(hide yes)
			)
		)
		(property "Value" "GND"
			(at 169.545 205.105 0)
			(effects
				(font
					(size 1.27 1.27)
					(thickness 0.15)
				)
				(justify left bottom)
			)
		)
		(property "Footprint" ""
			(at 180.34 208.28 0)
			(effects
				(font
					(size 1.27 1.27)
					(thickness 0.15)
				)
				(justify left bottom)
				(hide yes)
			)
		)
		(property "Datasheet" ""
			(at 180.34 213.36 0)
			(effects
				(font
					(size 1.27 1.27)
					(thickness 0.15)
				)
				(justify left bottom)
				(hide yes)
			)
		)
		(property "Description" ""
			(at 180.34 215.9 0)
			(effects
				(font
					(size 1.27 1.27)
				)
				(justify left bottom)
				(hide yes)
			)
		)
		(property "Author" "Antmicro"
			(at 180.34 208.28 0)
			(effects
				(font
					(size 1.27 1.27)
					(thickness 0.15)
				)
				(justify left bottom)
				(hide yes)
			)
		)
		(property "License" "Apache-2.0"
			(at 180.34 210.82 0)
			(effects
				(font
					(size 1.27 1.27)
					(thickness 0.15)
				)
				(justify left bottom)
				(hide yes)
			)
		)
		(pin "1"
		)
		(instances
			(project "sodimm-ddr5-tester"
				(path ""
					(reference "#PWR0436")
					(unit 1)
				)
			)
		)
	)
	(symbol
		(lib_id "antmicroTestPoints:TP_1mm_SMD")
		(at 261.62 273.05 270)
		(unit 1)
		(exclude_from_sim no)
		(in_bom yes)
		(on_board yes)
		(dnp no)
		(property "Reference" "TP38"
			(at 261.62 278.0228 90)
			(effects
				(font
					(size 1.27 1.27)
				)
			)
		)
		(property "Value" "TP_1mm_SMD"
			(at 254 288.29 0)
			(effects
				(font
					(size 1.27 1.27)
					(thickness 0.15)
				)
				(justify left bottom)
				(hide yes)
			)
		)
		(property "Footprint" "antmicro-footprints:TP_SMD_1mm"
			(at 251.46 288.29 0)
			(effects
				(font
					(size 1.27 1.27)
					(thickness 0.15)
				)
				(justify left bottom)
				(hide yes)
			)
		)
		(property "Datasheet" ""
			(at 248.92 288.29 0)
			(effects
				(font
					(size 1.27 1.27)
					(thickness 0.15)
				)
				(justify left bottom)
				(hide yes)
			)
		)
		(property "Description" ""
			(at 261.62 273.05 0)
			(effects
				(font
					(size 1.27 1.27)
				)
			)
		)
		(property "MPN" ""
			(at 261.62 273.05 0)
			(effects
				(font
					(size 1.27 1.27)
				)
				(hide yes)
			)
		)
		(property "Manufacturer" ""
			(at 261.62 273.05 0)
			(effects
				(font
					(size 1.27 1.27)
				)
				(hide yes)
			)
		)
		(property "Author" "Antmicro"
			(at 246.38 288.29 0)
			(effects
				(font
					(size 1.27 1.27)
					(thickness 0.15)
				)
				(justify left bottom)
				(hide yes)
			)
		)
		(property "License" "Apache-2.0"
			(at 243.84 288.29 0)
			(effects
				(font
					(size 1.27 1.27)
					(thickness 0.15)
				)
				(justify left bottom)
				(hide yes)
			)
		)
		(pin "1"
		)
		(instances
			(project "sodimm-ddr5-tester"
				(path ""
					(reference "TP38")
					(unit 1)
				)
			)
		)
	)
	(symbol
		(lib_id "antmicropower:+3V3")
		(at 68.58 50.165 0)
		(unit 1)
		(exclude_from_sim no)
		(in_bom yes)
		(on_board yes)
		(dnp no)
		(fields_autoplaced yes)
		(property "Reference" "#PWR0267"
			(at 68.58 53.975 0)
			(effects
				(font
					(size 1.27 1.27)
				)
				(hide yes)
			)
		)
		(property "Value" "+3V3"
			(at 65.405 47.625 0)
			(effects
				(font
					(size 1.27 1.27)
					(thickness 0.15)
				)
				(justify left bottom)
			)
		)
		(property "Footprint" ""
			(at 83.82 57.785 0)
			(effects
				(font
					(size 1.27 1.27)
					(thickness 0.15)
				)
				(justify left bottom)
				(hide yes)
			)
		)
		(property "Datasheet" ""
			(at 83.82 60.325 0)
			(effects
				(font
					(size 1.27 1.27)
					(thickness 0.15)
				)
				(justify left bottom)
				(hide yes)
			)
		)
		(property "Description" ""
			(at 68.58 50.165 0)
			(effects
				(font
					(size 1.27 1.27)
				)
			)
		)
		(property "Author" "Antmicro"
			(at 83.82 52.705 0)
			(effects
				(font
					(size 1.27 1.27)
					(thickness 0.15)
				)
				(justify left bottom)
				(hide yes)
			)
		)
		(property "License" "Apache-2.0"
			(at 83.82 55.245 0)
			(effects
				(font
					(size 1.27 1.27)
					(thickness 0.15)
				)
				(justify left bottom)
				(hide yes)
			)
		)
		(pin "1"
		)
		(instances
			(project "sodimm-ddr5-tester"
				(path ""
					(reference "#PWR0267")
					(unit 1)
				)
			)
		)
	)
	(symbol
		(lib_id "antmicroMemory:AT24CS01_SOT23")
		(at 326.39 77.47 0)
		(mirror y)
		(unit 1)
		(exclude_from_sim no)
		(in_bom yes)
		(on_board yes)
		(dnp no)
		(property "Reference" "U34"
			(at 316.23 69.85 0)
			(effects
				(font
					(size 1.27 1.27)
					(thickness 0.15)
				)
			)
		)
		(property "Value" "AT24CS01_SOT23"
			(at 290.83 82.55 0)
			(effects
				(font
					(size 1.27 1.27)
					(thickness 0.15)
				)
				(justify left bottom)
				(hide yes)
			)
		)
		(property "Footprint" "antmicro-footprints:SOT-23-5"
			(at 290.83 85.09 0)
			(effects
				(font
					(size 1.27 1.27)
					(thickness 0.15)
				)
				(justify left bottom)
				(hide yes)
			)
		)
		(property "Datasheet" "http://ww1.microchip.com/downloads/en/devicedoc/Atmel-8815-SEEPROM-AT24CS01-02-Datasheet.pdf"
			(at 290.83 87.63 0)
			(effects
				(font
					(size 1.27 1.27)
					(thickness 0.15)
				)
				(justify left bottom)
				(hide yes)
			)
		)
		(property "Description" "EEPROM Memory IC 1Kbit I²C 1 MHz 550 ns SOT-23-5"
			(at 290.83 100.33 0)
			(effects
				(font
					(size 1.27 1.27)
				)
				(justify left bottom)
				(hide yes)
			)
		)
		(property "Manufacturer" "Atmel"
			(at 290.83 90.17 0)
			(effects
				(font
					(size 1.27 1.27)
					(thickness 0.15)
				)
				(justify left bottom)
				(hide yes)
			)
		)
		(property "MPN" "AT24CS01-ST"
			(at 316.23 72.39 0)
			(effects
				(font
					(size 1.27 1.27)
					(thickness 0.15)
				)
			)
		)
		(property "Author" "Antmicro"
			(at 290.83 95.25 0)
			(effects
				(font
					(size 1.27 1.27)
					(thickness 0.15)
				)
				(justify left bottom)
				(hide yes)
			)
		)
		(property "License" "Apache-2.0"
			(at 290.83 97.79 0)
			(effects
				(font
					(size 1.27 1.27)
					(thickness 0.15)
				)
				(justify left bottom)
				(hide yes)
			)
		)
		(pin "3"
		)
		(pin "1"
		)
		(pin "2"
		)
		(pin "4"
		)
		(pin "5"
		)
		(instances
			(project ""
				(path ""
					(reference "U34")
					(unit 1)
				)
			)
		)
	)
	(symbol
		(lib_id "antmicroDiodesRectifiersSingle:BAT54-02V-G3-08")
		(at 288.29 74.93 180)
		(unit 1)
		(exclude_from_sim no)
		(in_bom yes)
		(on_board yes)
		(dnp no)
		(property "Reference" "D17"
			(at 286.004 70.358 0)
			(effects
				(font
					(size 1.27 1.27)
					(thickness 0.15)
				)
			)
		)
		(property "Value" "BAT54-02V-G3-08"
			(at 266.7 59.69 0)
			(effects
				(font
					(size 1.27 1.27)
					(thickness 0.15)
				)
				(justify left bottom)
				(hide yes)
			)
		)
		(property "Footprint" "antmicro-footprints:SOD-523"
			(at 266.7 64.77 0)
			(effects
				(font
					(size 1.27 1.27)
					(thickness 0.15)
				)
				(justify left bottom)
				(hide yes)
			)
		)
		(property "Datasheet" "https://www.vishay.com/docs/85633/bat5402v.pdf"
			(at 266.7 62.23 0)
			(effects
				(font
					(size 1.27 1.27)
					(thickness 0.15)
				)
				(justify left bottom)
				(hide yes)
			)
		)
		(property "Description" "Small Signal Schottky Diode, Single, 30 V, 200 mA, 800 mV, 600 mA, 125 °C"
			(at 266.7 49.53 0)
			(effects
				(font
					(size 1.27 1.27)
				)
				(justify left bottom)
				(hide yes)
			)
		)
		(property "MPN" "BAT54-02V-G3-08"
			(at 286.004 72.644 0)
			(effects
				(font
					(size 1.27 1.27)
					(thickness 0.15)
				)
			)
		)
		(property "Manufacturer" "Vishay"
			(at 266.7 57.15 0)
			(effects
				(font
					(size 1.27 1.27)
					(thickness 0.15)
				)
				(justify left bottom)
				(hide yes)
			)
		)
		(property "Author" "Antmicro"
			(at 266.7 54.61 0)
			(effects
				(font
					(size 1.27 1.27)
					(thickness 0.15)
				)
				(justify left bottom)
				(hide yes)
			)
		)
		(property "License" "Apache-2.0"
			(at 266.7 52.07 0)
			(effects
				(font
					(size 1.27 1.27)
					(thickness 0.15)
				)
				(justify left bottom)
				(hide yes)
			)
		)
		(pin "2"
		)
		(pin "1"
		)
		(instances
			(project ""
				(path ""
					(reference "D17")
					(unit 1)
				)
			)
		)
	)
	(symbol
		(lib_id "antmicropower:GND")
		(at 267.97 274.32 0)
		(mirror y)
		(unit 1)
		(exclude_from_sim no)
		(in_bom yes)
		(on_board yes)
		(dnp no)
		(property "Reference" "#PWR043"
			(at 267.97 280.67 0)
			(effects
				(font
					(size 1.27 1.27)
				)
				(hide yes)
			)
		)
		(property "Value" "GND"
			(at 265.938 278.13 0)
			(effects
				(font
					(size 1.27 1.27)
					(thickness 0.15)
				)
				(justify right)
			)
		)
		(property "Footprint" ""
			(at 259.08 281.94 0)
			(effects
				(font
					(size 1.27 1.27)
					(thickness 0.15)
				)
				(justify left bottom)
				(hide yes)
			)
		)
		(property "Datasheet" ""
			(at 259.08 287.02 0)
			(effects
				(font
					(size 1.27 1.27)
					(thickness 0.15)
				)
				(justify left bottom)
				(hide yes)
			)
		)
		(property "Description" ""
			(at 259.08 289.56 0)
			(effects
				(font
					(size 1.27 1.27)
				)
				(justify left bottom)
				(hide yes)
			)
		)
		(property "Author" "Antmicro"
			(at 259.08 281.94 0)
			(effects
				(font
					(size 1.27 1.27)
					(thickness 0.15)
				)
				(justify left bottom)
				(hide yes)
			)
		)
		(property "License" "Apache-2.0"
			(at 259.08 284.48 0)
			(effects
				(font
					(size 1.27 1.27)
					(thickness 0.15)
				)
				(justify left bottom)
				(hide yes)
			)
		)
		(pin "1"
		)
		(instances
			(project "sodimm-ddr5-tester"
				(path ""
					(reference "#PWR043")
					(unit 1)
				)
			)
		)
	)
	(symbol
		(lib_id "antmicropower:GND")
		(at 81.915 57.785 0)
		(mirror y)
		(unit 1)
		(exclude_from_sim no)
		(in_bom yes)
		(on_board yes)
		(dnp no)
		(fields_autoplaced yes)
		(property "Reference" "#PWR0269"
			(at 81.915 64.135 0)
			(effects
				(font
					(size 1.27 1.27)
				)
				(hide yes)
			)
		)
		(property "Value" "GND"
			(at 83.82 59.055 0)
			(effects
				(font
					(size 1.27 1.27)
					(thickness 0.15)
				)
				(justify right)
			)
		)
		(property "Footprint" ""
			(at 73.025 65.405 0)
			(effects
				(font
					(size 1.27 1.27)
					(thickness 0.15)
				)
				(justify left bottom)
				(hide yes)
			)
		)
		(property "Datasheet" ""
			(at 73.025 70.485 0)
			(effects
				(font
					(size 1.27 1.27)
					(thickness 0.15)
				)
				(justify left bottom)
				(hide yes)
			)
		)
		(property "Description" ""
			(at 73.025 73.025 0)
			(effects
				(font
					(size 1.27 1.27)
				)
				(justify left bottom)
				(hide yes)
			)
		)
		(property "Author" "Antmicro"
			(at 73.025 65.405 0)
			(effects
				(font
					(size 1.27 1.27)
					(thickness 0.15)
				)
				(justify left bottom)
				(hide yes)
			)
		)
		(property "License" "Apache-2.0"
			(at 73.025 67.945 0)
			(effects
				(font
					(size 1.27 1.27)
					(thickness 0.15)
				)
				(justify left bottom)
				(hide yes)
			)
		)
		(pin "1"
		)
		(instances
			(project "sodimm-ddr5-tester"
				(path ""
					(reference "#PWR0269")
					(unit 1)
				)
			)
		)
	)
	(symbol
		(lib_id "antmicroInterfaceAnalogSwitchesMultiplexersDemultiplexers:TS5A3359_VSSOP")
		(at 143.51 210.82 0)
		(unit 1)
		(exclude_from_sim no)
		(in_bom yes)
		(on_board yes)
		(dnp no)
		(fields_autoplaced yes)
		(property "Reference" "U24"
			(at 156.845 204.595 0)
			(effects
				(font
					(size 1.27 1.27)
					(thickness 0.15)
				)
			)
		)
		(property "Value" "TS5A3359_VSSOP"
			(at 156.845 207.1187 0)
			(effects
				(font
					(size 1.27 1.27)
					(thickness 0.15)
				)
			)
		)
		(property "Footprint" "antmicro-footprints:VSSOP-8_2.3x2mm_P0.5mm"
			(at 185.42 218.44 0)
			(effects
				(font
					(size 1.27 1.27)
					(thickness 0.15)
				)
				(justify left bottom)
				(hide yes)
			)
		)
		(property "Datasheet" "https://www.ti.com/general/docs/suppproductinfo.tsp?distId=26&gotoUrl=http%3A%2F%2Fwww.ti.com%2Flit%2Fgpn%2Fts5a3359"
			(at 185.42 220.98 0)
			(effects
				(font
					(size 1.27 1.27)
					(thickness 0.15)
				)
				(justify left bottom)
				(hide yes)
			)
		)
		(property "Description" ""
			(at 143.51 210.82 0)
			(effects
				(font
					(size 1.27 1.27)
				)
			)
		)
		(property "MPN" "TS5A3359DCUR"
			(at 185.42 223.52 0)
			(effects
				(font
					(size 1.27 1.27)
					(thickness 0.15)
				)
				(justify left bottom)
				(hide yes)
			)
		)
		(property "Manufacturer" "Texas Instruments"
			(at 185.42 226.06 0)
			(effects
				(font
					(size 1.27 1.27)
					(thickness 0.15)
				)
				(justify left bottom)
				(hide yes)
			)
		)
		(property "Author" "Antmicro"
			(at 185.42 228.6 0)
			(effects
				(font
					(size 1.27 1.27)
					(thickness 0.15)
				)
				(justify left bottom)
				(hide yes)
			)
		)
		(property "License" "Apache-2.0"
			(at 185.42 231.14 0)
			(effects
				(font
					(size 1.27 1.27)
					(thickness 0.15)
				)
				(justify left bottom)
				(hide yes)
			)
		)
		(pin "1"
		)
		(pin "2"
		)
		(pin "3"
		)
		(pin "4"
		)
		(pin "5"
		)
		(pin "6"
		)
		(pin "7"
		)
		(pin "8"
		)
		(instances
			(project "sodimm-ddr5-tester"
				(path ""
					(reference "U24")
					(unit 1)
				)
			)
		)
	)
	(symbol
		(lib_id "antmicroResistors0402:R_0R_0402")
		(at 292.1 198.755 180)
		(unit 1)
		(exclude_from_sim no)
		(in_bom no)
		(on_board yes)
		(dnp yes)
		(property "Reference" "R175"
			(at 291.465 197.485 0)
			(effects
				(font
					(size 1.27 1.27)
				)
				(justify right)
			)
		)
		(property "Value" "R_0R_0402"
			(at 271.78 186.055 0)
			(effects
				(font
					(size 1.27 1.27)
					(thickness 0.15)
				)
				(justify left bottom)
				(hide yes)
			)
		)
		(property "Footprint" "antmicro-footprints:R_0402_1005Metric"
			(at 271.78 183.515 0)
			(effects
				(font
					(size 1.27 1.27)
					(thickness 0.15)
				)
				(justify left bottom)
				(hide yes)
			)
		)
		(property "Datasheet" "https://industrial.panasonic.com/cdbs/www-data/pdf/RDA0000/AOA0000C301.pdf"
			(at 271.78 180.975 0)
			(effects
				(font
					(size 1.27 1.27)
					(thickness 0.15)
				)
				(justify left bottom)
				(hide yes)
			)
		)
		(property "Description" ""
			(at 292.1 198.755 0)
			(effects
				(font
					(size 1.27 1.27)
				)
			)
		)
		(property "Manufacturer" "Panasonic"
			(at 271.78 175.895 0)
			(effects
				(font
					(size 1.27 1.27)
					(thickness 0.15)
				)
				(justify left bottom)
				(hide yes)
			)
		)
		(property "MPN" "ERJ2GE0R00X"
			(at 271.78 178.435 0)
			(effects
				(font
					(size 1.27 1.27)
					(thickness 0.15)
				)
				(justify left bottom)
				(hide yes)
			)
		)
		(property "Val" "0R"
			(at 284.48 197.485 0)
			(effects
				(font
					(size 1.27 1.27)
					(thickness 0.15)
				)
				(justify right)
			)
		)
		(property "License" "Apache-2.0"
			(at 271.78 173.355 0)
			(effects
				(font
					(size 1.27 1.27)
					(thickness 0.15)
				)
				(justify left bottom)
				(hide yes)
			)
		)
		(property "Author" "Antmicro"
			(at 271.78 170.815 0)
			(effects
				(font
					(size 1.27 1.27)
					(thickness 0.15)
				)
				(justify left bottom)
				(hide yes)
			)
		)
		(property "Tolerance" "~"
			(at 271.78 188.595 0)
			(effects
				(font
					(size 1.27 1.27)
				)
				(justify left bottom)
				(hide yes)
			)
		)
		(property "Current" "1A"
			(at 293.3699 196.215 90)
			(effects
				(font
					(size 1.27 1.27)
					(thickness 0.15)
				)
				(justify right)
				(hide yes)
			)
		)
		(pin "1"
		)
		(pin "2"
		)
		(instances
			(project "sodimm-ddr5-tester"
				(path ""
					(reference "R175")
					(unit 1)
				)
			)
		)
	)
	(symbol
		(lib_id "antmicropower:+3V3_AON")
		(at 185.42 209.55 0)
		(mirror y)
		(unit 1)
		(exclude_from_sim no)
		(in_bom yes)
		(on_board yes)
		(dnp no)
		(fields_autoplaced yes)
		(property "Reference" "#PWR0440"
			(at 185.42 213.36 0)
			(effects
				(font
					(size 1.27 1.27)
				)
				(hide yes)
			)
		)
		(property "Value" "+3V3_AON"
			(at 185.42 203.835 0)
			(effects
				(font
					(size 1.27 1.27)
				)
			)
		)
		(property "Footprint" ""
			(at 185.42 209.55 0)
			(effects
				(font
					(size 1.27 1.27)
				)
				(hide yes)
			)
		)
		(property "Datasheet" ""
			(at 185.42 209.55 0)
			(effects
				(font
					(size 1.27 1.27)
				)
				(hide yes)
			)
		)
		(property "Description" ""
			(at 185.42 209.55 0)
			(effects
				(font
					(size 1.27 1.27)
				)
			)
		)
		(pin "1"
		)
		(instances
			(project "sodimm-ddr5-tester"
				(path ""
					(reference "#PWR0440")
					(unit 1)
				)
			)
		)
	)
	(symbol
		(lib_id "antmicroCapacitors0402:C_100n_0402")
		(at 185.42 194.31 270)
		(mirror x)
		(unit 1)
		(exclude_from_sim no)
		(in_bom yes)
		(on_board yes)
		(dnp no)
		(fields_autoplaced yes)
		(property "Reference" "C196"
			(at 182.88 190.4935 90)
			(effects
				(font
					(size 1.27 1.27)
				)
				(justify right)
			)
		)
		(property "Value" "C_100n_0402"
			(at 175.26 173.99 0)
			(effects
				(font
					(size 1.27 1.27)
					(thickness 0.15)
				)
				(justify left bottom)
				(hide yes)
			)
		)
		(property "Footprint" "antmicro-footprints:C_0402_1005Metric"
			(at 172.72 173.99 0)
			(effects
				(font
					(size 1.27 1.27)
					(thickness 0.15)
				)
				(justify left bottom)
				(hide yes)
			)
		)
		(property "Datasheet" "https://www.murata.com/products/productdetail?partno=GRM155R61H104KE14%23"
			(at 170.18 173.99 0)
			(effects
				(font
					(size 1.27 1.27)
					(thickness 0.15)
				)
				(justify left bottom)
				(hide yes)
			)
		)
		(property "Description" ""
			(at 185.42 194.31 0)
			(effects
				(font
					(size 1.27 1.27)
				)
			)
		)
		(property "Manufacturer" "Murata"
			(at 165.1 173.99 0)
			(effects
				(font
					(size 1.27 1.27)
					(thickness 0.15)
				)
				(justify left bottom)
				(hide yes)
			)
		)
		(property "MPN" "GRM155R61H104KE14D"
			(at 167.64 173.99 0)
			(effects
				(font
					(size 1.27 1.27)
					(thickness 0.15)
				)
				(justify left bottom)
				(hide yes)
			)
		)
		(property "Val" "100n"
			(at 182.88 193.0335 90)
			(effects
				(font
					(size 1.27 1.27)
					(thickness 0.15)
				)
				(justify right)
			)
		)
		(property "License" "Apache-2.0"
			(at 162.56 173.99 0)
			(effects
				(font
					(size 1.27 1.27)
					(thickness 0.15)
				)
				(justify left bottom)
				(hide yes)
			)
		)
		(property "Author" "Antmicro"
			(at 160.02 173.99 0)
			(effects
				(font
					(size 1.27 1.27)
					(thickness 0.15)
				)
				(justify left bottom)
				(hide yes)
			)
		)
		(property "Voltage" "50V"
			(at 157.48 173.99 0)
			(effects
				(font
					(size 1.27 1.27)
				)
				(justify left bottom)
				(hide yes)
			)
		)
		(property "Dielectric" "X5R"
			(at 154.94 173.99 0)
			(effects
				(font
					(size 1.27 1.27)
				)
				(justify left bottom)
				(hide yes)
			)
		)
		(pin "1"
		)
		(pin "2"
		)
		(instances
			(project "sodimm-ddr5-tester"
				(path ""
					(reference "C196")
					(unit 1)
				)
			)
		)
	)
	(symbol
		(lib_id "antmicropower:+3V3")
		(at 273.05 73.66 0)
		(unit 1)
		(exclude_from_sim no)
		(in_bom yes)
		(on_board yes)
		(dnp no)
		(fields_autoplaced yes)
		(property "Reference" "#PWR0313"
			(at 273.05 77.47 0)
			(effects
				(font
					(size 1.27 1.27)
				)
				(hide yes)
			)
		)
		(property "Value" "+3V3"
			(at 269.875 71.12 0)
			(effects
				(font
					(size 1.27 1.27)
					(thickness 0.15)
				)
				(justify left bottom)
			)
		)
		(property "Footprint" ""
			(at 288.29 81.28 0)
			(effects
				(font
					(size 1.27 1.27)
					(thickness 0.15)
				)
				(justify left bottom)
				(hide yes)
			)
		)
		(property "Datasheet" ""
			(at 288.29 83.82 0)
			(effects
				(font
					(size 1.27 1.27)
					(thickness 0.15)
				)
				(justify left bottom)
				(hide yes)
			)
		)
		(property "Description" ""
			(at 273.05 73.66 0)
			(effects
				(font
					(size 1.27 1.27)
				)
			)
		)
		(property "Author" "Antmicro"
			(at 288.29 76.2 0)
			(effects
				(font
					(size 1.27 1.27)
					(thickness 0.15)
				)
				(justify left bottom)
				(hide yes)
			)
		)
		(property "License" "Apache-2.0"
			(at 288.29 78.74 0)
			(effects
				(font
					(size 1.27 1.27)
					(thickness 0.15)
				)
				(justify left bottom)
				(hide yes)
			)
		)
		(pin "1"
		)
		(instances
			(project "sodimm-ddr5-tester"
				(path ""
					(reference "#PWR0313")
					(unit 1)
				)
			)
		)
	)
	(symbol
		(lib_id "antmicropower:GND")
		(at 185.42 220.345 0)
		(mirror y)
		(unit 1)
		(exclude_from_sim no)
		(in_bom yes)
		(on_board yes)
		(dnp no)
		(fields_autoplaced yes)
		(property "Reference" "#PWR0438"
			(at 185.42 226.695 0)
			(effects
				(font
					(size 1.27 1.27)
				)
				(hide yes)
			)
		)
		(property "Value" "GND"
			(at 187.96 221.615 0)
			(effects
				(font
					(size 1.27 1.27)
					(thickness 0.15)
				)
				(justify right)
			)
		)
		(property "Footprint" ""
			(at 176.53 227.965 0)
			(effects
				(font
					(size 1.27 1.27)
					(thickness 0.15)
				)
				(justify left bottom)
				(hide yes)
			)
		)
		(property "Datasheet" ""
			(at 176.53 233.045 0)
			(effects
				(font
					(size 1.27 1.27)
					(thickness 0.15)
				)
				(justify left bottom)
				(hide yes)
			)
		)
		(property "Description" ""
			(at 176.53 235.585 0)
			(effects
				(font
					(size 1.27 1.27)
				)
				(justify left bottom)
				(hide yes)
			)
		)
		(property "Author" "Antmicro"
			(at 176.53 227.965 0)
			(effects
				(font
					(size 1.27 1.27)
					(thickness 0.15)
				)
				(justify left bottom)
				(hide yes)
			)
		)
		(property "License" "Apache-2.0"
			(at 176.53 230.505 0)
			(effects
				(font
					(size 1.27 1.27)
					(thickness 0.15)
				)
				(justify left bottom)
				(hide yes)
			)
		)
		(pin "1"
		)
		(instances
			(project "sodimm-ddr5-tester"
				(path ""
					(reference "#PWR0438")
					(unit 1)
				)
			)
		)
	)
	(symbol
		(lib_id "antmicroResistors0402:R_0R_0402")
		(at 340.36 80.01 180)
		(unit 1)
		(exclude_from_sim no)
		(in_bom yes)
		(on_board yes)
		(dnp no)
		(property "Reference" "R37"
			(at 335.788 82.296 0)
			(effects
				(font
					(size 1.27 1.27)
				)
				(justify right)
			)
		)
		(property "Value" "R_0R_0402"
			(at 320.04 67.31 0)
			(effects
				(font
					(size 1.27 1.27)
					(thickness 0.15)
				)
				(justify left bottom)
				(hide yes)
			)
		)
		(property "Footprint" "antmicro-footprints:R_0402_1005Metric"
			(at 320.04 64.77 0)
			(effects
				(font
					(size 1.27 1.27)
					(thickness 0.15)
				)
				(justify left bottom)
				(hide yes)
			)
		)
		(property "Datasheet" "https://industrial.panasonic.com/cdbs/www-data/pdf/RDA0000/AOA0000C301.pdf"
			(at 320.04 62.23 0)
			(effects
				(font
					(size 1.27 1.27)
					(thickness 0.15)
				)
				(justify left bottom)
				(hide yes)
			)
		)
		(property "Description" ""
			(at 340.36 80.01 0)
			(effects
				(font
					(size 1.27 1.27)
				)
			)
		)
		(property "Manufacturer" "Panasonic"
			(at 320.04 57.15 0)
			(effects
				(font
					(size 1.27 1.27)
					(thickness 0.15)
				)
				(justify left bottom)
				(hide yes)
			)
		)
		(property "MPN" "ERJ2GE0R00X"
			(at 320.04 59.69 0)
			(effects
				(font
					(size 1.27 1.27)
					(thickness 0.15)
				)
				(justify left bottom)
				(hide yes)
			)
		)
		(property "Val" "0R"
			(at 336.55 80.01 0)
			(effects
				(font
					(size 1.27 1.27)
					(thickness 0.15)
				)
				(justify right)
			)
		)
		(property "License" "Apache-2.0"
			(at 320.04 54.61 0)
			(effects
				(font
					(size 1.27 1.27)
					(thickness 0.15)
				)
				(justify left bottom)
				(hide yes)
			)
		)
		(property "Author" "Antmicro"
			(at 320.04 52.07 0)
			(effects
				(font
					(size 1.27 1.27)
					(thickness 0.15)
				)
				(justify left bottom)
				(hide yes)
			)
		)
		(property "Tolerance" "~"
			(at 320.04 69.85 0)
			(effects
				(font
					(size 1.27 1.27)
				)
				(justify left bottom)
				(hide yes)
			)
		)
		(property "Current" "1A"
			(at 341.6299 77.47 90)
			(effects
				(font
					(size 1.27 1.27)
					(thickness 0.15)
				)
				(justify right)
				(hide yes)
			)
		)
		(pin "1"
		)
		(pin "2"
		)
		(instances
			(project "sodimm-ddr5-tester"
				(path ""
					(reference "R37")
					(unit 1)
				)
			)
		)
	)
	(symbol
		(lib_id "antmicropower:+1V0")
		(at 139.065 55.88 0)
		(mirror y)
		(unit 1)
		(exclude_from_sim no)
		(in_bom yes)
		(on_board yes)
		(dnp no)
		(fields_autoplaced yes)
		(property "Reference" "#PWR0272"
			(at 139.065 59.69 0)
			(effects
				(font
					(size 1.27 1.27)
				)
				(hide yes)
			)
		)
		(property "Value" "+1V0"
			(at 139.065 52.324 0)
			(effects
				(font
					(size 1.27 1.27)
				)
			)
		)
		(property "Footprint" ""
			(at 139.065 55.88 0)
			(effects
				(font
					(size 1.27 1.27)
				)
				(hide yes)
			)
		)
		(property "Datasheet" ""
			(at 139.065 55.88 0)
			(effects
				(font
					(size 1.27 1.27)
				)
				(hide yes)
			)
		)
		(property "Description" ""
			(at 139.065 55.88 0)
			(effects
				(font
					(size 1.27 1.27)
				)
			)
		)
		(pin "1"
		)
		(instances
			(project "sodimm-ddr5-tester"
				(path ""
					(reference "#PWR0272")
					(unit 1)
				)
			)
		)
	)
	(symbol
		(lib_id "antmicropower:PWR_FLAG")
		(at 133.35 75.565 0)
		(unit 1)
		(exclude_from_sim no)
		(in_bom yes)
		(on_board yes)
		(dnp no)
		(fields_autoplaced yes)
		(property "Reference" "#FLG0107"
			(at 133.35 73.66 0)
			(effects
				(font
					(size 1.27 1.27)
				)
				(hide yes)
			)
		)
		(property "Value" "PWR_FLAG"
			(at 133.35 71.9892 0)
			(effects
				(font
					(size 1.27 1.27)
				)
			)
		)
		(property "Footprint" ""
			(at 133.35 75.565 0)
			(effects
				(font
					(size 1.27 1.27)
				)
				(hide yes)
			)
		)
		(property "Datasheet" ""
			(at 133.35 75.565 0)
			(effects
				(font
					(size 1.27 1.27)
				)
				(hide yes)
			)
		)
		(property "Description" ""
			(at 133.35 75.565 0)
			(effects
				(font
					(size 1.27 1.27)
				)
			)
		)
		(pin "1"
		)
		(instances
			(project "sodimm-ddr5-tester"
				(path ""
					(reference "#FLG0107")
					(unit 1)
				)
			)
		)
	)
	(symbol
		(lib_id "antmicroCapacitors0402:C_100n_0402")
		(at 68.58 52.705 90)
		(mirror x)
		(unit 1)
		(exclude_from_sim no)
		(in_bom yes)
		(on_board yes)
		(dnp no)
		(fields_autoplaced yes)
		(property "Reference" "C165"
			(at 71.12 53.9813 90)
			(effects
				(font
					(size 1.27 1.27)
				)
				(justify right)
			)
		)
		(property "Value" "C_100n_0402"
			(at 78.74 73.025 0)
			(effects
				(font
					(size 1.27 1.27)
					(thickness 0.15)
				)
				(justify left bottom)
				(hide yes)
			)
		)
		(property "Footprint" "antmicro-footprints:C_0402_1005Metric"
			(at 81.28 73.025 0)
			(effects
				(font
					(size 1.27 1.27)
					(thickness 0.15)
				)
				(justify left bottom)
				(hide yes)
			)
		)
		(property "Datasheet" "https://www.murata.com/products/productdetail?partno=GRM155R61H104KE14%23"
			(at 83.82 73.025 0)
			(effects
				(font
					(size 1.27 1.27)
					(thickness 0.15)
				)
				(justify left bottom)
				(hide yes)
			)
		)
		(property "Description" ""
			(at 68.58 52.705 0)
			(effects
				(font
					(size 1.27 1.27)
				)
			)
		)
		(property "Manufacturer" "Murata"
			(at 88.9 73.025 0)
			(effects
				(font
					(size 1.27 1.27)
					(thickness 0.15)
				)
				(justify left bottom)
				(hide yes)
			)
		)
		(property "MPN" "GRM155R61H104KE14D"
			(at 86.36 73.025 0)
			(effects
				(font
					(size 1.27 1.27)
					(thickness 0.15)
				)
				(justify left bottom)
				(hide yes)
			)
		)
		(property "Val" "100n"
			(at 71.12 57.1562 90)
			(effects
				(font
					(size 1.27 1.27)
					(thickness 0.15)
				)
				(justify right)
			)
		)
		(property "License" "Apache-2.0"
			(at 91.44 73.025 0)
			(effects
				(font
					(size 1.27 1.27)
					(thickness 0.15)
				)
				(justify left bottom)
				(hide yes)
			)
		)
		(property "Author" "Antmicro"
			(at 93.98 73.025 0)
			(effects
				(font
					(size 1.27 1.27)
					(thickness 0.15)
				)
				(justify left bottom)
				(hide yes)
			)
		)
		(property "Voltage" "50V"
			(at 96.52 73.025 0)
			(effects
				(font
					(size 1.27 1.27)
				)
				(justify left bottom)
				(hide yes)
			)
		)
		(property "Dielectric" "X5R"
			(at 99.06 73.025 0)
			(effects
				(font
					(size 1.27 1.27)
				)
				(justify left bottom)
				(hide yes)
			)
		)
		(pin "1"
		)
		(pin "2"
		)
		(instances
			(project "sodimm-ddr5-tester"
				(path ""
					(reference "C165")
					(unit 1)
				)
			)
		)
	)
	(symbol
		(lib_id "antmicroResistors0402:R_4k7_0402")
		(at 83.185 76.835 270)
		(unit 1)
		(exclude_from_sim no)
		(in_bom yes)
		(on_board yes)
		(dnp no)
		(property "Reference" "R122"
			(at 81.915 78.105 90)
			(effects
				(font
					(size 1.27 1.27)
				)
				(justify right)
			)
		)
		(property "Value" "R_4k7_0402"
			(at 70.485 97.155 0)
			(effects
				(font
					(size 1.27 1.27)
					(thickness 0.15)
				)
				(justify left bottom)
				(hide yes)
			)
		)
		(property "Footprint" "antmicro-footprints:R_0402_1005Metric"
			(at 67.945 97.155 0)
			(effects
				(font
					(size 1.27 1.27)
					(thickness 0.15)
				)
				(justify left bottom)
				(hide yes)
			)
		)
		(property "Datasheet" "https://www.bourns.com/docs/product-datasheets/cr.pdf"
			(at 65.405 97.155 0)
			(effects
				(font
					(size 1.27 1.27)
					(thickness 0.15)
				)
				(justify left bottom)
				(hide yes)
			)
		)
		(property "Description" ""
			(at 83.185 76.835 0)
			(effects
				(font
					(size 1.27 1.27)
				)
			)
		)
		(property "Manufacturer" "Bourns"
			(at 60.325 97.155 0)
			(effects
				(font
					(size 1.27 1.27)
					(thickness 0.15)
				)
				(justify left bottom)
				(hide yes)
			)
		)
		(property "MPN" "CR0402-FX-4701GLF"
			(at 62.865 97.155 0)
			(effects
				(font
					(size 1.27 1.27)
					(thickness 0.15)
				)
				(justify left bottom)
				(hide yes)
			)
		)
		(property "Val" "4k7"
			(at 81.915 81.28 90)
			(effects
				(font
					(size 1.27 1.27)
					(thickness 0.15)
				)
				(justify right)
			)
		)
		(property "License" "Apache-2.0"
			(at 57.785 97.155 0)
			(effects
				(font
					(size 1.27 1.27)
					(thickness 0.15)
				)
				(justify left bottom)
				(hide yes)
			)
		)
		(property "Author" "Antmicro"
			(at 55.245 97.155 0)
			(effects
				(font
					(size 1.27 1.27)
					(thickness 0.15)
				)
				(justify left bottom)
				(hide yes)
			)
		)
		(property "Tolerance" "1%"
			(at 73.025 97.155 0)
			(effects
				(font
					(size 1.27 1.27)
				)
				(justify left bottom)
				(hide yes)
			)
		)
		(pin "1"
		)
		(pin "2"
		)
		(instances
			(project "sodimm-ddr5-tester"
				(path ""
					(reference "R122")
					(unit 1)
				)
			)
		)
	)
	(symbol
		(lib_id "antmicroInterfaceAnalogSwitchesMultiplexersDemultiplexers:TS5A3359_VSSOP")
		(at 143.51 186.69 0)
		(unit 1)
		(exclude_from_sim no)
		(in_bom yes)
		(on_board yes)
		(dnp no)
		(fields_autoplaced yes)
		(property "Reference" "U23"
			(at 156.845 180.465 0)
			(effects
				(font
					(size 1.27 1.27)
					(thickness 0.15)
				)
			)
		)
		(property "Value" "TS5A3359_VSSOP"
			(at 156.845 182.9887 0)
			(effects
				(font
					(size 1.27 1.27)
					(thickness 0.15)
				)
			)
		)
		(property "Footprint" "antmicro-footprints:VSSOP-8_2.3x2mm_P0.5mm"
			(at 185.42 194.31 0)
			(effects
				(font
					(size 1.27 1.27)
					(thickness 0.15)
				)
				(justify left bottom)
				(hide yes)
			)
		)
		(property "Datasheet" "https://www.ti.com/general/docs/suppproductinfo.tsp?distId=26&gotoUrl=http%3A%2F%2Fwww.ti.com%2Flit%2Fgpn%2Fts5a3359"
			(at 185.42 196.85 0)
			(effects
				(font
					(size 1.27 1.27)
					(thickness 0.15)
				)
				(justify left bottom)
				(hide yes)
			)
		)
		(property "Description" ""
			(at 143.51 186.69 0)
			(effects
				(font
					(size 1.27 1.27)
				)
			)
		)
		(property "MPN" "TS5A3359DCUR"
			(at 185.42 199.39 0)
			(effects
				(font
					(size 1.27 1.27)
					(thickness 0.15)
				)
				(justify left bottom)
				(hide yes)
			)
		)
		(property "Manufacturer" "Texas Instruments"
			(at 185.42 201.93 0)
			(effects
				(font
					(size 1.27 1.27)
					(thickness 0.15)
				)
				(justify left bottom)
				(hide yes)
			)
		)
		(property "Author" "Antmicro"
			(at 185.42 204.47 0)
			(effects
				(font
					(size 1.27 1.27)
					(thickness 0.15)
				)
				(justify left bottom)
				(hide yes)
			)
		)
		(property "License" "Apache-2.0"
			(at 185.42 207.01 0)
			(effects
				(font
					(size 1.27 1.27)
					(thickness 0.15)
				)
				(justify left bottom)
				(hide yes)
			)
		)
		(pin "1"
		)
		(pin "2"
		)
		(pin "3"
		)
		(pin "4"
		)
		(pin "5"
		)
		(pin "6"
		)
		(pin "7"
		)
		(pin "8"
		)
		(instances
			(project "sodimm-ddr5-tester"
				(path ""
					(reference "U23")
					(unit 1)
				)
			)
		)
	)
	(symbol
		(lib_id "antmicropower:GND")
		(at 68.58 57.785 0)
		(mirror y)
		(unit 1)
		(exclude_from_sim no)
		(in_bom yes)
		(on_board yes)
		(dnp no)
		(fields_autoplaced yes)
		(property "Reference" "#PWR0268"
			(at 68.58 64.135 0)
			(effects
				(font
					(size 1.27 1.27)
				)
				(hide yes)
			)
		)
		(property "Value" "GND"
			(at 71.12 59.055 0)
			(effects
				(font
					(size 1.27 1.27)
					(thickness 0.15)
				)
				(justify right)
			)
		)
		(property "Footprint" ""
			(at 59.69 65.405 0)
			(effects
				(font
					(size 1.27 1.27)
					(thickness 0.15)
				)
				(justify left bottom)
				(hide yes)
			)
		)
		(property "Datasheet" ""
			(at 59.69 70.485 0)
			(effects
				(font
					(size 1.27 1.27)
					(thickness 0.15)
				)
				(justify left bottom)
				(hide yes)
			)
		)
		(property "Description" ""
			(at 59.69 73.025 0)
			(effects
				(font
					(size 1.27 1.27)
				)
				(justify left bottom)
				(hide yes)
			)
		)
		(property "Author" "Antmicro"
			(at 59.69 65.405 0)
			(effects
				(font
					(size 1.27 1.27)
					(thickness 0.15)
				)
				(justify left bottom)
				(hide yes)
			)
		)
		(property "License" "Apache-2.0"
			(at 59.69 67.945 0)
			(effects
				(font
					(size 1.27 1.27)
					(thickness 0.15)
				)
				(justify left bottom)
				(hide yes)
			)
		)
		(pin "1"
		)
		(instances
			(project "sodimm-ddr5-tester"
				(path ""
					(reference "#PWR0268")
					(unit 1)
				)
			)
		)
	)
	(symbol
		(lib_id "antmicroTestPoints:TP_1mm_SMD")
		(at 334.01 76.2 90)
		(unit 1)
		(exclude_from_sim no)
		(in_bom yes)
		(on_board yes)
		(dnp no)
		(property "Reference" "TP70"
			(at 334.01 71.2272 90)
			(effects
				(font
					(size 1.27 1.27)
				)
			)
		)
		(property "Value" "TP_1mm_SMD"
			(at 341.63 60.96 0)
			(effects
				(font
					(size 1.27 1.27)
					(thickness 0.15)
				)
				(justify left bottom)
				(hide yes)
			)
		)
		(property "Footprint" "antmicro-footprints:TP_SMD_1mm"
			(at 344.17 60.96 0)
			(effects
				(font
					(size 1.27 1.27)
					(thickness 0.15)
				)
				(justify left bottom)
				(hide yes)
			)
		)
		(property "Datasheet" ""
			(at 346.71 60.96 0)
			(effects
				(font
					(size 1.27 1.27)
					(thickness 0.15)
				)
				(justify left bottom)
				(hide yes)
			)
		)
		(property "Description" ""
			(at 334.01 76.2 0)
			(effects
				(font
					(size 1.27 1.27)
				)
			)
		)
		(property "MPN" ""
			(at 334.01 76.2 0)
			(effects
				(font
					(size 1.27 1.27)
				)
				(hide yes)
			)
		)
		(property "Manufacturer" ""
			(at 334.01 76.2 0)
			(effects
				(font
					(size 1.27 1.27)
				)
				(hide yes)
			)
		)
		(property "Author" "Antmicro"
			(at 349.25 60.96 0)
			(effects
				(font
					(size 1.27 1.27)
					(thickness 0.15)
				)
				(justify left bottom)
				(hide yes)
			)
		)
		(property "License" "Apache-2.0"
			(at 351.79 60.96 0)
			(effects
				(font
					(size 1.27 1.27)
					(thickness 0.15)
				)
				(justify left bottom)
				(hide yes)
			)
		)
		(pin "1"
		)
		(instances
			(project "sodimm-ddr5-tester"
				(path ""
					(reference "TP70")
					(unit 1)
				)
			)
		)
	)
	(symbol
		(lib_id "antmicroResistors0402:R_0R_0402")
		(at 292.1 210.185 180)
		(unit 1)
		(exclude_from_sim no)
		(in_bom no)
		(on_board yes)
		(dnp yes)
		(property "Reference" "R179"
			(at 291.465 208.915 0)
			(effects
				(font
					(size 1.27 1.27)
				)
				(justify right)
			)
		)
		(property "Value" "R_0R_0402"
			(at 271.78 197.485 0)
			(effects
				(font
					(size 1.27 1.27)
					(thickness 0.15)
				)
				(justify left bottom)
				(hide yes)
			)
		)
		(property "Footprint" "antmicro-footprints:R_0402_1005Metric"
			(at 271.78 194.945 0)
			(effects
				(font
					(size 1.27 1.27)
					(thickness 0.15)
				)
				(justify left bottom)
				(hide yes)
			)
		)
		(property "Datasheet" "https://industrial.panasonic.com/cdbs/www-data/pdf/RDA0000/AOA0000C301.pdf"
			(at 271.78 192.405 0)
			(effects
				(font
					(size 1.27 1.27)
					(thickness 0.15)
				)
				(justify left bottom)
				(hide yes)
			)
		)
		(property "Description" ""
			(at 292.1 210.185 0)
			(effects
				(font
					(size 1.27 1.27)
				)
			)
		)
		(property "Manufacturer" "Panasonic"
			(at 271.78 187.325 0)
			(effects
				(font
					(size 1.27 1.27)
					(thickness 0.15)
				)
				(justify left bottom)
				(hide yes)
			)
		)
		(property "MPN" "ERJ2GE0R00X"
			(at 271.78 189.865 0)
			(effects
				(font
					(size 1.27 1.27)
					(thickness 0.15)
				)
				(justify left bottom)
				(hide yes)
			)
		)
		(property "Val" "0R"
			(at 284.48 208.915 0)
			(effects
				(font
					(size 1.27 1.27)
					(thickness 0.15)
				)
				(justify right)
			)
		)
		(property "License" "Apache-2.0"
			(at 271.78 184.785 0)
			(effects
				(font
					(size 1.27 1.27)
					(thickness 0.15)
				)
				(justify left bottom)
				(hide yes)
			)
		)
		(property "Author" "Antmicro"
			(at 271.78 182.245 0)
			(effects
				(font
					(size 1.27 1.27)
					(thickness 0.15)
				)
				(justify left bottom)
				(hide yes)
			)
		)
		(property "Tolerance" "~"
			(at 271.78 200.025 0)
			(effects
				(font
					(size 1.27 1.27)
				)
				(justify left bottom)
				(hide yes)
			)
		)
		(property "Current" "1A"
			(at 293.3699 207.645 90)
			(effects
				(font
					(size 1.27 1.27)
					(thickness 0.15)
				)
				(justify right)
				(hide yes)
			)
		)
		(pin "1"
		)
		(pin "2"
		)
		(instances
			(project "sodimm-ddr5-tester"
				(path ""
					(reference "R179")
					(unit 1)
				)
			)
		)
	)
	(symbol
		(lib_id "antmicroResistors0402:R_0R_0402")
		(at 292.1 205.105 180)
		(unit 1)
		(exclude_from_sim no)
		(in_bom no)
		(on_board yes)
		(dnp yes)
		(property "Reference" "R177"
			(at 291.465 203.835 0)
			(effects
				(font
					(size 1.27 1.27)
				)
				(justify right)
			)
		)
		(property "Value" "R_0R_0402"
			(at 271.78 192.405 0)
			(effects
				(font
					(size 1.27 1.27)
					(thickness 0.15)
				)
				(justify left bottom)
				(hide yes)
			)
		)
		(property "Footprint" "antmicro-footprints:R_0402_1005Metric"
			(at 271.78 189.865 0)
			(effects
				(font
					(size 1.27 1.27)
					(thickness 0.15)
				)
				(justify left bottom)
				(hide yes)
			)
		)
		(property "Datasheet" "https://industrial.panasonic.com/cdbs/www-data/pdf/RDA0000/AOA0000C301.pdf"
			(at 271.78 187.325 0)
			(effects
				(font
					(size 1.27 1.27)
					(thickness 0.15)
				)
				(justify left bottom)
				(hide yes)
			)
		)
		(property "Description" ""
			(at 292.1 205.105 0)
			(effects
				(font
					(size 1.27 1.27)
				)
			)
		)
		(property "Manufacturer" "Panasonic"
			(at 271.78 182.245 0)
			(effects
				(font
					(size 1.27 1.27)
					(thickness 0.15)
				)
				(justify left bottom)
				(hide yes)
			)
		)
		(property "MPN" "ERJ2GE0R00X"
			(at 271.78 184.785 0)
			(effects
				(font
					(size 1.27 1.27)
					(thickness 0.15)
				)
				(justify left bottom)
				(hide yes)
			)
		)
		(property "Val" "0R"
			(at 284.48 203.835 0)
			(effects
				(font
					(size 1.27 1.27)
					(thickness 0.15)
				)
				(justify right)
			)
		)
		(property "License" "Apache-2.0"
			(at 271.78 179.705 0)
			(effects
				(font
					(size 1.27 1.27)
					(thickness 0.15)
				)
				(justify left bottom)
				(hide yes)
			)
		)
		(property "Author" "Antmicro"
			(at 271.78 177.165 0)
			(effects
				(font
					(size 1.27 1.27)
					(thickness 0.15)
				)
				(justify left bottom)
				(hide yes)
			)
		)
		(property "Tolerance" "~"
			(at 271.78 194.945 0)
			(effects
				(font
					(size 1.27 1.27)
				)
				(justify left bottom)
				(hide yes)
			)
		)
		(property "Current" "1A"
			(at 293.3699 202.565 90)
			(effects
				(font
					(size 1.27 1.27)
					(thickness 0.15)
				)
				(justify right)
				(hide yes)
			)
		)
		(pin "1"
		)
		(pin "2"
		)
		(instances
			(project "sodimm-ddr5-tester"
				(path ""
					(reference "R177")
					(unit 1)
				)
			)
		)
	)
	(symbol
		(lib_id "antmicropower:GND")
		(at 283.21 85.09 0)
		(mirror y)
		(unit 1)
		(exclude_from_sim no)
		(in_bom yes)
		(on_board yes)
		(dnp no)
		(property "Reference" "#PWR0317"
			(at 283.21 91.44 0)
			(effects
				(font
					(size 1.27 1.27)
				)
				(hide yes)
			)
		)
		(property "Value" "GND"
			(at 281.178 88.9 0)
			(effects
				(font
					(size 1.27 1.27)
					(thickness 0.15)
				)
				(justify right)
			)
		)
		(property "Footprint" ""
			(at 274.32 92.71 0)
			(effects
				(font
					(size 1.27 1.27)
					(thickness 0.15)
				)
				(justify left bottom)
				(hide yes)
			)
		)
		(property "Datasheet" ""
			(at 274.32 97.79 0)
			(effects
				(font
					(size 1.27 1.27)
					(thickness 0.15)
				)
				(justify left bottom)
				(hide yes)
			)
		)
		(property "Description" ""
			(at 274.32 100.33 0)
			(effects
				(font
					(size 1.27 1.27)
				)
				(justify left bottom)
				(hide yes)
			)
		)
		(property "Author" "Antmicro"
			(at 274.32 92.71 0)
			(effects
				(font
					(size 1.27 1.27)
					(thickness 0.15)
				)
				(justify left bottom)
				(hide yes)
			)
		)
		(property "License" "Apache-2.0"
			(at 274.32 95.25 0)
			(effects
				(font
					(size 1.27 1.27)
					(thickness 0.15)
				)
				(justify left bottom)
				(hide yes)
			)
		)
		(pin "1"
		)
		(instances
			(project "sodimm-ddr5-tester"
				(path ""
					(reference "#PWR0317")
					(unit 1)
				)
			)
		)
	)
	(symbol
		(lib_id "antmicropower:GND")
		(at 327.66 85.09 0)
		(unit 1)
		(exclude_from_sim no)
		(in_bom yes)
		(on_board yes)
		(dnp no)
		(property "Reference" "#PWR0316"
			(at 327.66 91.44 0)
			(effects
				(font
					(size 1.27 1.27)
				)
				(hide yes)
			)
		)
		(property "Value" "GND"
			(at 325.628 89.027 0)
			(effects
				(font
					(size 1.27 1.27)
					(thickness 0.15)
				)
				(justify left)
			)
		)
		(property "Footprint" ""
			(at 336.55 92.71 0)
			(effects
				(font
					(size 1.27 1.27)
					(thickness 0.15)
				)
				(justify left bottom)
				(hide yes)
			)
		)
		(property "Datasheet" ""
			(at 336.55 97.79 0)
			(effects
				(font
					(size 1.27 1.27)
					(thickness 0.15)
				)
				(justify left bottom)
				(hide yes)
			)
		)
		(property "Description" ""
			(at 336.55 100.33 0)
			(effects
				(font
					(size 1.27 1.27)
				)
				(justify left bottom)
				(hide yes)
			)
		)
		(property "Author" "Antmicro"
			(at 336.55 92.71 0)
			(effects
				(font
					(size 1.27 1.27)
					(thickness 0.15)
				)
				(justify left bottom)
				(hide yes)
			)
		)
		(property "License" "Apache-2.0"
			(at 336.55 95.25 0)
			(effects
				(font
					(size 1.27 1.27)
					(thickness 0.15)
				)
				(justify left bottom)
				(hide yes)
			)
		)
		(pin "1"
		)
		(instances
			(project "sodimm-ddr5-tester"
				(path ""
					(reference "#PWR0316")
					(unit 1)
				)
			)
		)
	)
	(symbol
		(lib_id "antmicropower:GND")
		(at 171.45 224.79 0)
		(unit 1)
		(exclude_from_sim no)
		(in_bom yes)
		(on_board yes)
		(dnp no)
		(property "Reference" "#PWR0439"
			(at 171.45 231.14 0)
			(effects
				(font
					(size 1.27 1.27)
				)
				(hide yes)
			)
		)
		(property "Value" "GND"
			(at 169.545 229.235 0)
			(effects
				(font
					(size 1.27 1.27)
					(thickness 0.15)
				)
				(justify left bottom)
			)
		)
		(property "Footprint" ""
			(at 180.34 232.41 0)
			(effects
				(font
					(size 1.27 1.27)
					(thickness 0.15)
				)
				(justify left bottom)
				(hide yes)
			)
		)
		(property "Datasheet" ""
			(at 180.34 237.49 0)
			(effects
				(font
					(size 1.27 1.27)
					(thickness 0.15)
				)
				(justify left bottom)
				(hide yes)
			)
		)
		(property "Description" ""
			(at 180.34 240.03 0)
			(effects
				(font
					(size 1.27 1.27)
				)
				(justify left bottom)
				(hide yes)
			)
		)
		(property "Author" "Antmicro"
			(at 180.34 232.41 0)
			(effects
				(font
					(size 1.27 1.27)
					(thickness 0.15)
				)
				(justify left bottom)
				(hide yes)
			)
		)
		(property "License" "Apache-2.0"
			(at 180.34 234.95 0)
			(effects
				(font
					(size 1.27 1.27)
					(thickness 0.15)
				)
				(justify left bottom)
				(hide yes)
			)
		)
		(pin "1"
		)
		(instances
			(project "sodimm-ddr5-tester"
				(path ""
					(reference "#PWR0439")
					(unit 1)
				)
			)
		)
	)
	(symbol
		(lib_id "antmicroResistors0402:R_0R_0402")
		(at 139.065 57.785 90)
		(mirror x)
		(unit 1)
		(exclude_from_sim no)
		(in_bom no)
		(on_board yes)
		(dnp yes)
		(property "Reference" "R126"
			(at 137.16 59.69 90)
			(effects
				(font
					(size 1.27 1.27)
					(thickness 0.15)
				)
				(justify left)
			)
		)
		(property "Value" "R_0R_0402"
			(at 151.765 78.105 0)
			(effects
				(font
					(size 1.27 1.27)
					(thickness 0.15)
				)
				(justify left bottom)
				(hide yes)
			)
		)
		(property "Footprint" "antmicro-footprints:R_0402_1005Metric"
			(at 154.305 78.105 0)
			(effects
				(font
					(size 1.27 1.27)
					(thickness 0.15)
				)
				(justify left bottom)
				(hide yes)
			)
		)
		(property "Datasheet" "https://industrial.panasonic.com/cdbs/www-data/pdf/RDA0000/AOA0000C301.pdf"
			(at 156.845 78.105 0)
			(effects
				(font
					(size 1.27 1.27)
					(thickness 0.15)
				)
				(justify left bottom)
				(hide yes)
			)
		)
		(property "Description" ""
			(at 139.065 57.785 0)
			(effects
				(font
					(size 1.27 1.27)
				)
			)
		)
		(property "MPN" "ERJ2GE0R00X"
			(at 159.385 78.105 0)
			(effects
				(font
					(size 1.27 1.27)
					(thickness 0.15)
				)
				(justify left bottom)
				(hide yes)
			)
		)
		(property "Manufacturer" "Panasonic"
			(at 161.925 78.105 0)
			(effects
				(font
					(size 1.27 1.27)
					(thickness 0.15)
				)
				(justify left bottom)
				(hide yes)
			)
		)
		(property "License" "Apache-2.0"
			(at 164.465 78.105 0)
			(effects
				(font
					(size 1.27 1.27)
					(thickness 0.15)
				)
				(justify left bottom)
				(hide yes)
			)
		)
		(property "Author" "Antmicro"
			(at 167.005 78.105 0)
			(effects
				(font
					(size 1.27 1.27)
					(thickness 0.15)
				)
				(justify left bottom)
				(hide yes)
			)
		)
		(property "Val" "0R"
			(at 137.16 62.2137 90)
			(effects
				(font
					(size 1.27 1.27)
					(thickness 0.15)
				)
				(justify left)
			)
		)
		(property "Tolerance" "~"
			(at 149.225 78.105 0)
			(effects
				(font
					(size 1.27 1.27)
				)
				(justify left bottom)
				(hide yes)
			)
		)
		(property "Current" "1A"
			(at 169.545 78.105 0)
			(effects
				(font
					(size 1.27 1.27)
					(thickness 0.15)
				)
				(justify left bottom)
				(hide yes)
			)
		)
		(pin "1"
		)
		(pin "2"
		)
		(instances
			(project "sodimm-ddr5-tester"
				(path ""
					(reference "R126")
					(unit 1)
				)
			)
		)
	)
	(symbol
		(lib_id "antmicroTestPoints:TP_1mm_SMD")
		(at 274.32 273.05 270)
		(unit 1)
		(exclude_from_sim no)
		(in_bom yes)
		(on_board yes)
		(dnp no)
		(property "Reference" "TP40"
			(at 274.32 278.0228 90)
			(effects
				(font
					(size 1.27 1.27)
				)
			)
		)
		(property "Value" "TP_1mm_SMD"
			(at 266.7 288.29 0)
			(effects
				(font
					(size 1.27 1.27)
					(thickness 0.15)
				)
				(justify left bottom)
				(hide yes)
			)
		)
		(property "Footprint" "antmicro-footprints:TP_SMD_1mm"
			(at 264.16 288.29 0)
			(effects
				(font
					(size 1.27 1.27)
					(thickness 0.15)
				)
				(justify left bottom)
				(hide yes)
			)
		)
		(property "Datasheet" ""
			(at 261.62 288.29 0)
			(effects
				(font
					(size 1.27 1.27)
					(thickness 0.15)
				)
				(justify left bottom)
				(hide yes)
			)
		)
		(property "Description" ""
			(at 274.32 273.05 0)
			(effects
				(font
					(size 1.27 1.27)
				)
			)
		)
		(property "MPN" ""
			(at 274.32 273.05 0)
			(effects
				(font
					(size 1.27 1.27)
				)
				(hide yes)
			)
		)
		(property "Manufacturer" ""
			(at 274.32 273.05 0)
			(effects
				(font
					(size 1.27 1.27)
				)
				(hide yes)
			)
		)
		(property "Author" "Antmicro"
			(at 259.08 288.29 0)
			(effects
				(font
					(size 1.27 1.27)
					(thickness 0.15)
				)
				(justify left bottom)
				(hide yes)
			)
		)
		(property "License" "Apache-2.0"
			(at 256.54 288.29 0)
			(effects
				(font
					(size 1.27 1.27)
					(thickness 0.15)
				)
				(justify left bottom)
				(hide yes)
			)
		)
		(pin "1"
		)
		(instances
			(project "sodimm-ddr5-tester"
				(path ""
					(reference "TP40")
					(unit 1)
				)
			)
		)
	)
	(symbol
		(lib_id "antmicroResistors0402:R_4k7_0402")
		(at 123.19 177.8 270)
		(unit 1)
		(exclude_from_sim no)
		(in_bom yes)
		(on_board yes)
		(dnp no)
		(property "Reference" "R159"
			(at 124.46 179.07 90)
			(effects
				(font
					(size 1.27 1.27)
				)
				(justify left)
			)
		)
		(property "Value" "R_4k7_0402"
			(at 110.49 198.12 0)
			(effects
				(font
					(size 1.27 1.27)
					(thickness 0.15)
				)
				(justify left bottom)
				(hide yes)
			)
		)
		(property "Footprint" "antmicro-footprints:R_0402_1005Metric"
			(at 107.95 198.12 0)
			(effects
				(font
					(size 1.27 1.27)
					(thickness 0.15)
				)
				(justify left bottom)
				(hide yes)
			)
		)
		(property "Datasheet" "https://www.bourns.com/docs/product-datasheets/cr.pdf"
			(at 105.41 198.12 0)
			(effects
				(font
					(size 1.27 1.27)
					(thickness 0.15)
				)
				(justify left bottom)
				(hide yes)
			)
		)
		(property "Description" ""
			(at 123.19 177.8 0)
			(effects
				(font
					(size 1.27 1.27)
				)
			)
		)
		(property "Manufacturer" "Bourns"
			(at 100.33 198.12 0)
			(effects
				(font
					(size 1.27 1.27)
					(thickness 0.15)
				)
				(justify left bottom)
				(hide yes)
			)
		)
		(property "MPN" "CR0402-FX-4701GLF"
			(at 102.87 198.12 0)
			(effects
				(font
					(size 1.27 1.27)
					(thickness 0.15)
				)
				(justify left bottom)
				(hide yes)
			)
		)
		(property "Val" "4k7"
			(at 124.46 182.245 90)
			(effects
				(font
					(size 1.27 1.27)
					(thickness 0.15)
				)
				(justify left)
			)
		)
		(property "License" "Apache-2.0"
			(at 97.79 198.12 0)
			(effects
				(font
					(size 1.27 1.27)
					(thickness 0.15)
				)
				(justify left bottom)
				(hide yes)
			)
		)
		(property "Author" "Antmicro"
			(at 95.25 198.12 0)
			(effects
				(font
					(size 1.27 1.27)
					(thickness 0.15)
				)
				(justify left bottom)
				(hide yes)
			)
		)
		(property "Tolerance" "1%"
			(at 113.03 198.12 0)
			(effects
				(font
					(size 1.27 1.27)
				)
				(justify left bottom)
				(hide yes)
			)
		)
		(pin "1"
		)
		(pin "2"
		)
		(instances
			(project "sodimm-ddr5-tester"
				(path ""
					(reference "R159")
					(unit 1)
				)
			)
		)
	)
	(symbol
		(lib_id "antmicropower:+3V3")
		(at 83.185 74.295 0)
		(unit 1)
		(exclude_from_sim no)
		(in_bom yes)
		(on_board yes)
		(dnp no)
		(fields_autoplaced yes)
		(property "Reference" "#PWR0270"
			(at 83.185 78.105 0)
			(effects
				(font
					(size 1.27 1.27)
				)
				(hide yes)
			)
		)
		(property "Value" "+3V3"
			(at 80.01 71.755 0)
			(effects
				(font
					(size 1.27 1.27)
					(thickness 0.15)
				)
				(justify left bottom)
			)
		)
		(property "Footprint" ""
			(at 98.425 81.915 0)
			(effects
				(font
					(size 1.27 1.27)
					(thickness 0.15)
				)
				(justify left bottom)
				(hide yes)
			)
		)
		(property "Datasheet" ""
			(at 98.425 84.455 0)
			(effects
				(font
					(size 1.27 1.27)
					(thickness 0.15)
				)
				(justify left bottom)
				(hide yes)
			)
		)
		(property "Description" ""
			(at 83.185 74.295 0)
			(effects
				(font
					(size 1.27 1.27)
				)
			)
		)
		(property "Author" "Antmicro"
			(at 98.425 76.835 0)
			(effects
				(font
					(size 1.27 1.27)
					(thickness 0.15)
				)
				(justify left bottom)
				(hide yes)
			)
		)
		(property "License" "Apache-2.0"
			(at 98.425 79.375 0)
			(effects
				(font
					(size 1.27 1.27)
					(thickness 0.15)
				)
				(justify left bottom)
				(hide yes)
			)
		)
		(pin "1"
		)
		(instances
			(project "sodimm-ddr5-tester"
				(path ""
					(reference "#PWR0270")
					(unit 1)
				)
			)
		)
	)
	(symbol
		(lib_id "antmicroTestPoints:TP_1mm_SMD")
		(at 267.97 270.51 90)
		(unit 1)
		(exclude_from_sim no)
		(in_bom yes)
		(on_board yes)
		(dnp no)
		(property "Reference" "TP39"
			(at 267.97 265.5372 90)
			(effects
				(font
					(size 1.27 1.27)
				)
			)
		)
		(property "Value" "TP_1mm_SMD"
			(at 275.59 255.27 0)
			(effects
				(font
					(size 1.27 1.27)
					(thickness 0.15)
				)
				(justify left bottom)
				(hide yes)
			)
		)
		(property "Footprint" "antmicro-footprints:TP_SMD_1mm"
			(at 278.13 255.27 0)
			(effects
				(font
					(size 1.27 1.27)
					(thickness 0.15)
				)
				(justify left bottom)
				(hide yes)
			)
		)
		(property "Datasheet" ""
			(at 280.67 255.27 0)
			(effects
				(font
					(size 1.27 1.27)
					(thickness 0.15)
				)
				(justify left bottom)
				(hide yes)
			)
		)
		(property "Description" ""
			(at 267.97 270.51 0)
			(effects
				(font
					(size 1.27 1.27)
				)
			)
		)
		(property "MPN" ""
			(at 267.97 270.51 0)
			(effects
				(font
					(size 1.27 1.27)
				)
				(hide yes)
			)
		)
		(property "Manufacturer" ""
			(at 267.97 270.51 0)
			(effects
				(font
					(size 1.27 1.27)
				)
				(hide yes)
			)
		)
		(property "Author" "Antmicro"
			(at 283.21 255.27 0)
			(effects
				(font
					(size 1.27 1.27)
					(thickness 0.15)
				)
				(justify left bottom)
				(hide yes)
			)
		)
		(property "License" "Apache-2.0"
			(at 285.75 255.27 0)
			(effects
				(font
					(size 1.27 1.27)
					(thickness 0.15)
				)
				(justify left bottom)
				(hide yes)
			)
		)
		(pin "1"
		)
		(instances
			(project "sodimm-ddr5-tester"
				(path ""
					(reference "TP39")
					(unit 1)
				)
			)
		)
	)
	(symbol
		(lib_id "antmicroResistors0402:R_4k7_0402")
		(at 86.36 76.835 270)
		(unit 1)
		(exclude_from_sim no)
		(in_bom yes)
		(on_board yes)
		(dnp no)
		(property "Reference" "R123"
			(at 87.63 78.105 90)
			(effects
				(font
					(size 1.27 1.27)
				)
				(justify left)
			)
		)
		(property "Value" "R_4k7_0402"
			(at 73.66 97.155 0)
			(effects
				(font
					(size 1.27 1.27)
					(thickness 0.15)
				)
				(justify left bottom)
				(hide yes)
			)
		)
		(property "Footprint" "antmicro-footprints:R_0402_1005Metric"
			(at 71.12 97.155 0)
			(effects
				(font
					(size 1.27 1.27)
					(thickness 0.15)
				)
				(justify left bottom)
				(hide yes)
			)
		)
		(property "Datasheet" "https://www.bourns.com/docs/product-datasheets/cr.pdf"
			(at 68.58 97.155 0)
			(effects
				(font
					(size 1.27 1.27)
					(thickness 0.15)
				)
				(justify left bottom)
				(hide yes)
			)
		)
		(property "Description" ""
			(at 86.36 76.835 0)
			(effects
				(font
					(size 1.27 1.27)
				)
			)
		)
		(property "Manufacturer" "Bourns"
			(at 63.5 97.155 0)
			(effects
				(font
					(size 1.27 1.27)
					(thickness 0.15)
				)
				(justify left bottom)
				(hide yes)
			)
		)
		(property "MPN" "CR0402-FX-4701GLF"
			(at 66.04 97.155 0)
			(effects
				(font
					(size 1.27 1.27)
					(thickness 0.15)
				)
				(justify left bottom)
				(hide yes)
			)
		)
		(property "Val" "4k7"
			(at 87.63 81.28 90)
			(effects
				(font
					(size 1.27 1.27)
					(thickness 0.15)
				)
				(justify left)
			)
		)
		(property "License" "Apache-2.0"
			(at 60.96 97.155 0)
			(effects
				(font
					(size 1.27 1.27)
					(thickness 0.15)
				)
				(justify left bottom)
				(hide yes)
			)
		)
		(property "Author" "Antmicro"
			(at 58.42 97.155 0)
			(effects
				(font
					(size 1.27 1.27)
					(thickness 0.15)
				)
				(justify left bottom)
				(hide yes)
			)
		)
		(property "Tolerance" "1%"
			(at 76.2 97.155 0)
			(effects
				(font
					(size 1.27 1.27)
				)
				(justify left bottom)
				(hide yes)
			)
		)
		(pin "1"
		)
		(pin "2"
		)
		(instances
			(project "sodimm-ddr5-tester"
				(path ""
					(reference "R123")
					(unit 1)
				)
			)
		)
	)
	(symbol
		(lib_id "antmicroLogicTranslatorsLevelShifters:PCA9517ADP")
		(at 111.76 80.01 0)
		(mirror y)
		(unit 1)
		(exclude_from_sim no)
		(in_bom yes)
		(on_board yes)
		(dnp no)
		(property "Reference" "U16"
			(at 102.87 72.39 0)
			(effects
				(font
					(size 1.27 1.27)
					(thickness 0.15)
				)
			)
		)
		(property "Value" "PCA9517ADP"
			(at 102.87 74.93 0)
			(effects
				(font
					(size 1.27 1.27)
					(thickness 0.15)
				)
			)
		)
		(property "Footprint" "antmicro-footprints:TSSOP-8_3x3mm_P0.65mm"
			(at 78.74 87.63 0)
			(effects
				(font
					(size 1.27 1.27)
					(thickness 0.15)
				)
				(justify left bottom)
				(hide yes)
			)
		)
		(property "Datasheet" "https://www.nxp.com/docs/en/data-sheet/PCA9517A.pdf"
			(at 78.74 90.17 0)
			(effects
				(font
					(size 1.27 1.27)
					(thickness 0.15)
				)
				(justify left bottom)
				(hide yes)
			)
		)
		(property "Description" ""
			(at 111.76 80.01 0)
			(effects
				(font
					(size 1.27 1.27)
				)
			)
		)
		(property "MPN" "PCA9517ADP,118"
			(at 78.74 92.71 0)
			(effects
				(font
					(size 1.27 1.27)
					(thickness 0.15)
				)
				(justify left bottom)
				(hide yes)
			)
		)
		(property "Manufacturer" "NXP"
			(at 78.74 95.25 0)
			(effects
				(font
					(size 1.27 1.27)
					(thickness 0.15)
				)
				(justify left bottom)
				(hide yes)
			)
		)
		(property "Author" "Antmicro"
			(at 78.74 97.79 0)
			(effects
				(font
					(size 1.27 1.27)
					(thickness 0.15)
				)
				(justify left bottom)
				(hide yes)
			)
		)
		(property "License" "Apache-2.0"
			(at 78.74 100.33 0)
			(effects
				(font
					(size 1.27 1.27)
					(thickness 0.15)
				)
				(justify left bottom)
				(hide yes)
			)
		)
		(pin "1"
		)
		(pin "3"
		)
		(pin "7"
		)
		(pin "5"
		)
		(pin "2"
		)
		(pin "4"
		)
		(pin "8"
		)
		(pin "6"
		)
		(instances
			(project "sodimm-ddr5-tester"
				(path ""
					(reference "U16")
					(unit 1)
				)
			)
		)
	)
	(symbol
		(lib_id "antmicroTestPoints:TP_1mm_SMD")
		(at 281.94 81.28 180)
		(unit 1)
		(exclude_from_sim no)
		(in_bom yes)
		(on_board yes)
		(dnp no)
		(property "Reference" "TP68"
			(at 275.082 81.28 0)
			(effects
				(font
					(size 1.27 1.27)
				)
			)
		)
		(property "Value" "TP_1mm_SMD"
			(at 266.7 73.66 0)
			(effects
				(font
					(size 1.27 1.27)
					(thickness 0.15)
				)
				(justify left bottom)
				(hide yes)
			)
		)
		(property "Footprint" "antmicro-footprints:TP_SMD_1mm"
			(at 266.7 71.12 0)
			(effects
				(font
					(size 1.27 1.27)
					(thickness 0.15)
				)
				(justify left bottom)
				(hide yes)
			)
		)
		(property "Datasheet" ""
			(at 266.7 68.58 0)
			(effects
				(font
					(size 1.27 1.27)
					(thickness 0.15)
				)
				(justify left bottom)
				(hide yes)
			)
		)
		(property "Description" ""
			(at 281.94 81.28 0)
			(effects
				(font
					(size 1.27 1.27)
				)
			)
		)
		(property "MPN" ""
			(at 281.94 81.28 0)
			(effects
				(font
					(size 1.27 1.27)
				)
				(hide yes)
			)
		)
		(property "Manufacturer" ""
			(at 281.94 81.28 0)
			(effects
				(font
					(size 1.27 1.27)
				)
				(hide yes)
			)
		)
		(property "Author" "Antmicro"
			(at 266.7 66.04 0)
			(effects
				(font
					(size 1.27 1.27)
					(thickness 0.15)
				)
				(justify left bottom)
				(hide yes)
			)
		)
		(property "License" "Apache-2.0"
			(at 266.7 63.5 0)
			(effects
				(font
					(size 1.27 1.27)
					(thickness 0.15)
				)
				(justify left bottom)
				(hide yes)
			)
		)
		(pin "1"
		)
		(instances
			(project "sodimm-ddr5-tester"
				(path ""
					(reference "TP68")
					(unit 1)
				)
			)
		)
	)
	(symbol
		(lib_id "antmicropower:GND")
		(at 304.8 85.09 0)
		(unit 1)
		(exclude_from_sim no)
		(in_bom yes)
		(on_board yes)
		(dnp no)
		(property "Reference" "#PWR0208"
			(at 304.8 91.44 0)
			(effects
				(font
					(size 1.27 1.27)
				)
				(hide yes)
			)
		)
		(property "Value" "GND"
			(at 302.768 89.027 0)
			(effects
				(font
					(size 1.27 1.27)
					(thickness 0.15)
				)
				(justify left)
			)
		)
		(property "Footprint" ""
			(at 313.69 92.71 0)
			(effects
				(font
					(size 1.27 1.27)
					(thickness 0.15)
				)
				(justify left bottom)
				(hide yes)
			)
		)
		(property "Datasheet" ""
			(at 313.69 97.79 0)
			(effects
				(font
					(size 1.27 1.27)
					(thickness 0.15)
				)
				(justify left bottom)
				(hide yes)
			)
		)
		(property "Description" ""
			(at 313.69 100.33 0)
			(effects
				(font
					(size 1.27 1.27)
				)
				(justify left bottom)
				(hide yes)
			)
		)
		(property "Author" "Antmicro"
			(at 313.69 92.71 0)
			(effects
				(font
					(size 1.27 1.27)
					(thickness 0.15)
				)
				(justify left bottom)
				(hide yes)
			)
		)
		(property "License" "Apache-2.0"
			(at 313.69 95.25 0)
			(effects
				(font
					(size 1.27 1.27)
					(thickness 0.15)
				)
				(justify left bottom)
				(hide yes)
			)
		)
		(pin "1"
		)
		(instances
			(project "sodimm-ddr5-tester"
				(path ""
					(reference "#PWR0208")
					(unit 1)
				)
			)
		)
	)
	(symbol
		(lib_id "antmicroDiodesRectifiersSingle:BAT54-02V-G3-08")
		(at 288.29 77.47 180)
		(unit 1)
		(exclude_from_sim no)
		(in_bom yes)
		(on_board yes)
		(dnp no)
		(property "Reference" "D18"
			(at 285.75 79.756 0)
			(effects
				(font
					(size 1.27 1.27)
					(thickness 0.15)
				)
			)
		)
		(property "Value" "BAT54-02V-G3-08"
			(at 266.7 62.23 0)
			(effects
				(font
					(size 1.27 1.27)
					(thickness 0.15)
				)
				(justify left bottom)
				(hide yes)
			)
		)
		(property "Footprint" "antmicro-footprints:SOD-523"
			(at 266.7 67.31 0)
			(effects
				(font
					(size 1.27 1.27)
					(thickness 0.15)
				)
				(justify left bottom)
				(hide yes)
			)
		)
		(property "Datasheet" "https://www.vishay.com/docs/85633/bat5402v.pdf"
			(at 266.7 64.77 0)
			(effects
				(font
					(size 1.27 1.27)
					(thickness 0.15)
				)
				(justify left bottom)
				(hide yes)
			)
		)
		(property "Description" "Small Signal Schottky Diode, Single, 30 V, 200 mA, 800 mV, 600 mA, 125 °C"
			(at 266.7 52.07 0)
			(effects
				(font
					(size 1.27 1.27)
				)
				(justify left bottom)
				(hide yes)
			)
		)
		(property "MPN" "BAT54-02V-G3-08"
			(at 281.686 81.788 0)
			(effects
				(font
					(size 1.27 1.27)
					(thickness 0.15)
				)
				(hide yes)
			)
		)
		(property "Manufacturer" "Vishay"
			(at 266.7 59.69 0)
			(effects
				(font
					(size 1.27 1.27)
					(thickness 0.15)
				)
				(justify left bottom)
				(hide yes)
			)
		)
		(property "Author" "Antmicro"
			(at 266.7 57.15 0)
			(effects
				(font
					(size 1.27 1.27)
					(thickness 0.15)
				)
				(justify left bottom)
				(hide yes)
			)
		)
		(property "License" "Apache-2.0"
			(at 266.7 54.61 0)
			(effects
				(font
					(size 1.27 1.27)
					(thickness 0.15)
				)
				(justify left bottom)
				(hide yes)
			)
		)
		(pin "2"
		)
		(pin "1"
		)
		(instances
			(project "sodimm-ddr5-tester"
				(path ""
					(reference "D18")
					(unit 1)
				)
			)
		)
	)
	(symbol
		(lib_id "antmicropower:GND")
		(at 299.72 85.09 0)
		(unit 1)
		(exclude_from_sim no)
		(in_bom yes)
		(on_board yes)
		(dnp no)
		(property "Reference" "#PWR0312"
			(at 299.72 91.44 0)
			(effects
				(font
					(size 1.27 1.27)
				)
				(hide yes)
			)
		)
		(property "Value" "GND"
			(at 297.688 89.027 0)
			(effects
				(font
					(size 1.27 1.27)
					(thickness 0.15)
				)
				(justify left)
			)
		)
		(property "Footprint" ""
			(at 308.61 92.71 0)
			(effects
				(font
					(size 1.27 1.27)
					(thickness 0.15)
				)
				(justify left bottom)
				(hide yes)
			)
		)
		(property "Datasheet" ""
			(at 308.61 97.79 0)
			(effects
				(font
					(size 1.27 1.27)
					(thickness 0.15)
				)
				(justify left bottom)
				(hide yes)
			)
		)
		(property "Description" ""
			(at 308.61 100.33 0)
			(effects
				(font
					(size 1.27 1.27)
				)
				(justify left bottom)
				(hide yes)
			)
		)
		(property "Author" "Antmicro"
			(at 308.61 92.71 0)
			(effects
				(font
					(size 1.27 1.27)
					(thickness 0.15)
				)
				(justify left bottom)
				(hide yes)
			)
		)
		(property "License" "Apache-2.0"
			(at 308.61 95.25 0)
			(effects
				(font
					(size 1.27 1.27)
					(thickness 0.15)
				)
				(justify left bottom)
				(hide yes)
			)
		)
		(pin "1"
		)
		(instances
			(project "sodimm-ddr5-tester"
				(path ""
					(reference "#PWR0312")
					(unit 1)
				)
			)
		)
	)
	(symbol
		(lib_id "antmicropower:+1V8")
		(at 145.415 55.88 0)
		(mirror y)
		(unit 1)
		(exclude_from_sim no)
		(in_bom yes)
		(on_board yes)
		(dnp no)
		(fields_autoplaced yes)
		(property "Reference" "#PWR0273"
			(at 130.175 58.42 0)
			(effects
				(font
					(size 1.27 1.27)
					(thickness 0.15)
				)
				(justify left bottom)
				(hide yes)
			)
		)
		(property "Value" "+1V8"
			(at 148.59 53.34 0)
			(effects
				(font
					(size 1.27 1.27)
					(thickness 0.15)
				)
				(justify left bottom)
			)
		)
		(property "Footprint" ""
			(at 130.175 63.5 0)
			(effects
				(font
					(size 1.27 1.27)
					(thickness 0.15)
				)
				(justify left bottom)
				(hide yes)
			)
		)
		(property "Datasheet" ""
			(at 130.175 66.04 0)
			(effects
				(font
					(size 1.27 1.27)
					(thickness 0.15)
				)
				(justify left bottom)
				(hide yes)
			)
		)
		(property "Description" ""
			(at 145.415 55.88 0)
			(effects
				(font
					(size 1.27 1.27)
				)
			)
		)
		(property "Author" "Antmicro"
			(at 130.175 60.96 0)
			(effects
				(font
					(size 1.27 1.27)
					(thickness 0.15)
				)
				(justify left bottom)
				(hide yes)
			)
		)
		(property "License" "Apache-2.0"
			(at 130.175 63.5 0)
			(effects
				(font
					(size 1.27 1.27)
					(thickness 0.15)
				)
				(justify left bottom)
				(hide yes)
			)
		)
		(pin "1"
		)
		(instances
			(project "sodimm-ddr5-tester"
				(path ""
					(reference "#PWR0273")
					(unit 1)
				)
			)
		)
	)
	(symbol
		(lib_id "antmicropower:GND")
		(at 114.3 89.535 0)
		(unit 1)
		(exclude_from_sim no)
		(in_bom yes)
		(on_board yes)
		(dnp no)
		(property "Reference" "#PWR0271"
			(at 114.3 95.885 0)
			(effects
				(font
					(size 1.27 1.27)
				)
				(hide yes)
			)
		)
		(property "Value" "GND"
			(at 112.268 93.472 0)
			(effects
				(font
					(size 1.27 1.27)
					(thickness 0.15)
				)
				(justify left)
			)
		)
		(property "Footprint" ""
			(at 123.19 97.155 0)
			(effects
				(font
					(size 1.27 1.27)
					(thickness 0.15)
				)
				(justify left bottom)
				(hide yes)
			)
		)
		(property "Datasheet" ""
			(at 123.19 102.235 0)
			(effects
				(font
					(size 1.27 1.27)
					(thickness 0.15)
				)
				(justify left bottom)
				(hide yes)
			)
		)
		(property "Description" ""
			(at 123.19 104.775 0)
			(effects
				(font
					(size 1.27 1.27)
				)
				(justify left bottom)
				(hide yes)
			)
		)
		(property "Author" "Antmicro"
			(at 123.19 97.155 0)
			(effects
				(font
					(size 1.27 1.27)
					(thickness 0.15)
				)
				(justify left bottom)
				(hide yes)
			)
		)
		(property "License" "Apache-2.0"
			(at 123.19 99.695 0)
			(effects
				(font
					(size 1.27 1.27)
					(thickness 0.15)
				)
				(justify left bottom)
				(hide yes)
			)
		)
		(pin "1"
		)
		(instances
			(project "sodimm-ddr5-tester"
				(path ""
					(reference "#PWR0271")
					(unit 1)
				)
			)
		)
	)
)
